FILE_TYPE = MACRO_DRAWING;
SET COLOR_WIRE YELLOW;
SET COLOR_PROP ORANGE;
SET COLOR_DOT WHITE;
SET COLOR_ARC YELLOW;
SET COLOR_BODY GREEN;
SET COLOR_NOTE PURPLE;
SET PROP_DISPLAY VALUE;
SET PAGE_NUMBER P176;
FORCEADD UNIVERSAL_GND..1
(-8875 775);
FORCEPROP 3 LASTPIN (-8875 825) SIG_NAME GND\g
J 0
(-8865 835);
DISPLAY 0.659574 (-8865 835);
PAINT MONO (-8865 835);
DISPLAY INVISIBLE (-8865 835);
FORCEPROP 2 LAST CDS_LIB pure_quanta_power
J 0
(-8875 775);
PAINT MONO (-8875 775);
DISPLAY INVISIBLE (-8875 775);
FORCEPROP 1 LAST PATH I1
J 0
(-8800 775);
DISPLAY 0.872340 (-8800 775);
PAINT AQUA (-8800 775);
DISPLAY INVISIBLE (-8800 775);
FORCEPROP 1 LAST HDL_POWER GND
J 1
(-8850 700);
DISPLAY 0.872340 (-8850 700);
PAINT GREEN (-8850 700);
DISPLAY INVISIBLE (-8850 700);
FORCEADD VCC_CORE..1
(-1575 4575);
FORCEPROP 3 LASTPIN (-1575 4525) SIG_NAME PVDDCR_CPU1_P0\g
J 0
(-1565 4535);
DISPLAY 0.659574 (-1565 4535);
PAINT MONO (-1565 4535);
DISPLAY INVISIBLE (-1565 4535);
FORCEPROP 1 LAST HDL_POWER PVDDCR_CPU1_P0
J 1
(-1575 4625);
DISPLAY 0.489362 (-1575 4625);
PAINT GREEN (-1575 4625);
FORCEPROP 2 LAST CDS_LIB pure_quanta_power
J 0
(-1575 4575);
DISPLAY INVISIBLE (-1575 4575);
FORCEPROP 1 LAST PATH I106
J 0
(-1525 4600);
DISPLAY 0.872340 (-1525 4600);
PAINT AQUA (-1525 4600);
DISPLAY INVISIBLE (-1525 4600);
FORCEADD UNIVERSAL_GND..1
(-1575 3900);
FORCEPROP 3 LASTPIN (-1575 3950) SIG_NAME GND\g
J 0
(-1565 3960);
DISPLAY 0.659574 (-1565 3960);
PAINT MONO (-1565 3960);
DISPLAY INVISIBLE (-1565 3960);
FORCEPROP 2 LAST CDS_LIB pure_quanta_power
J 0
(-1575 3900);
PAINT MONO (-1575 3900);
DISPLAY INVISIBLE (-1575 3900);
FORCEPROP 1 LAST PATH I107
J 0
(-1500 3900);
DISPLAY 0.872340 (-1500 3900);
PAINT AQUA (-1500 3900);
DISPLAY INVISIBLE (-1500 3900);
FORCEPROP 1 LAST HDL_POWER GND
J 1
(-1550 3825);
DISPLAY 0.872340 (-1550 3825);
PAINT GREEN (-1550 3825);
DISPLAY INVISIBLE (-1550 3825);
FORCEADD Q_CAP..1
(-1875 4250);
FORCEPROP 1 LAST LOCATION PC105_1
J 0
(-1825 4375);
DISPLAY 0.489362 (-1825 4375);
PAINT SKYBLUE (-1825 4375);
FORCEPROP 0 LAST $SEC 1
J 0
(-1825 4425);
DISPLAY 0.680851 (-1825 4425);
PAINT MONO (-1825 4425);
DISPLAY INVISIBLE (-1825 4425);
FORCEPROP 0 LAST CDS_SEC 1
J 0
(-1825 4425);
DISPLAY 1.021277 (-1825 4425);
DISPLAY INVISIBLE (-1825 4425);
FORCEPROP 1 LASTPIN (-1875 4350) $PN 1
J 0
(-1865 4330);
DISPLAY 0.489362 (-1865 4330);
PAINT MONO (-1865 4330);
FORCEPROP 1 LASTPIN (-1875 4150) $PN 2
J 0
(-1865 4130);
DISPLAY 0.489362 (-1865 4130);
PAINT MONO (-1865 4130);
FORCEPROP 1 LAST TOLERANCE 20%
J 0
(-1825 4225);
DISPLAY 0.489362 (-1825 4225);
PAINT SKYBLUE (-1825 4225);
FORCEPROP 1 LAST VALUE 22UF
J 0
(-1825 4325);
DISPLAY 0.489362 (-1825 4325);
PAINT SKYBLUE (-1825 4325);
FORCEPROP 1 LAST VOLTAGE 4V
J 0
(-1825 4275);
DISPLAY 0.489362 (-1825 4275);
PAINT SKYBLUE (-1825 4275);
FORCEPROP 1 LAST PACK_TYPE 0805
J 0
(-1825 4125);
DISPLAY 0.489362 (-1825 4125);
PAINT SKYBLUE (-1825 4125);
FORCEPROP 1 LAST MATERIAL X6S
J 0
(-1825 4175);
DISPLAY 0.489362 (-1825 4175);
PAINT SKYBLUE (-1825 4175);
FORCEPROP 2 LAST CDS_LIB pure_quanta
J 0
(-1875 4250);
DISPLAY INVISIBLE (-1875 4250);
FORCEPROP 1 LAST PATH I108
J 0
(-1825 4400);
DISPLAY 0.978723 (-1825 4400);
PAINT WHITE (-1825 4400);
DISPLAY INVISIBLE (-1825 4400);
FORCEPROP 1 LAST PART_NUMBER TMP_QCH622KMEA01
J 0
(-1825 4075);
DISPLAY 0.489362 (-1825 4075);
PAINT SKYBLUE (-1825 4075);
DISPLAY INVISIBLE (-1825 4075);
FORCEADD Q_CAP..1
(-2300 4250);
FORCEPROP 1 LAST LOCATION PC102_1
J 0
(-2250 4375);
DISPLAY 0.489362 (-2250 4375);
PAINT SKYBLUE (-2250 4375);
FORCEPROP 0 LAST $SEC 1
J 0
(-2250 4425);
DISPLAY 0.680851 (-2250 4425);
PAINT MONO (-2250 4425);
DISPLAY INVISIBLE (-2250 4425);
FORCEPROP 0 LAST CDS_SEC 1
J 0
(-2250 4425);
DISPLAY 1.021277 (-2250 4425);
DISPLAY INVISIBLE (-2250 4425);
FORCEPROP 1 LASTPIN (-2300 4350) $PN 1
J 0
(-2290 4330);
DISPLAY 0.489362 (-2290 4330);
PAINT MONO (-2290 4330);
FORCEPROP 1 LASTPIN (-2300 4150) $PN 2
J 0
(-2290 4130);
DISPLAY 0.489362 (-2290 4130);
PAINT MONO (-2290 4130);
FORCEPROP 1 LAST MATERIAL X6S
J 0
(-2250 4175);
DISPLAY 0.489362 (-2250 4175);
PAINT SKYBLUE (-2250 4175);
FORCEPROP 1 LAST TOLERANCE 20%
J 0
(-2250 4225);
DISPLAY 0.489362 (-2250 4225);
PAINT SKYBLUE (-2250 4225);
FORCEPROP 1 LAST VALUE 22UF
J 0
(-2250 4325);
DISPLAY 0.489362 (-2250 4325);
PAINT SKYBLUE (-2250 4325);
FORCEPROP 1 LAST PART_NUMBER TMP_QCH622KMEA01
J 0
(-2250 4075);
DISPLAY 0.489362 (-2250 4075);
PAINT SKYBLUE (-2250 4075);
FORCEPROP 1 LAST VOLTAGE 4V
J 0
(-2250 4275);
DISPLAY 0.489362 (-2250 4275);
PAINT SKYBLUE (-2250 4275);
FORCEPROP 1 LAST PACK_TYPE 0805
J 0
(-2250 4125);
DISPLAY 0.489362 (-2250 4125);
PAINT SKYBLUE (-2250 4125);
FORCEPROP 2 LAST CDS_LIB pure_quanta
J 0
(-2300 4250);
DISPLAY INVISIBLE (-2300 4250);
FORCEPROP 1 LAST PATH I109
J 0
(-2250 4400);
DISPLAY 0.978723 (-2250 4400);
PAINT WHITE (-2250 4400);
DISPLAY INVISIBLE (-2250 4400);
FORCEADD Q_CAP..1
(-2700 4250);
FORCEPROP 1 LAST LOCATION PC99
J 0
(-2650 4375);
DISPLAY 0.489362 (-2650 4375);
PAINT SKYBLUE (-2650 4375);
FORCEPROP 0 LAST $SEC 1
J 0
(-2650 4425);
DISPLAY 0.680851 (-2650 4425);
PAINT MONO (-2650 4425);
DISPLAY INVISIBLE (-2650 4425);
FORCEPROP 0 LAST CDS_SEC 1
J 0
(-2650 4425);
DISPLAY 1.021277 (-2650 4425);
DISPLAY INVISIBLE (-2650 4425);
FORCEPROP 1 LASTPIN (-2700 4350) $PN 1
J 0
(-2690 4330);
DISPLAY 0.489362 (-2690 4330);
PAINT MONO (-2690 4330);
FORCEPROP 1 LASTPIN (-2700 4150) $PN 2
J 0
(-2690 4130);
DISPLAY 0.489362 (-2690 4130);
PAINT MONO (-2690 4130);
FORCEPROP 1 LAST MATERIAL X7R
J 0
(-2650 4175);
DISPLAY 0.489362 (-2650 4175);
PAINT SKYBLUE (-2650 4175);
FORCEPROP 1 LAST TOLERANCE 10%
J 0
(-2650 4225);
DISPLAY 0.489362 (-2650 4225);
PAINT SKYBLUE (-2650 4225);
FORCEPROP 1 LAST VALUE 0.1UF
J 0
(-2650 4325);
DISPLAY 0.489362 (-2650 4325);
PAINT SKYBLUE (-2650 4325);
FORCEPROP 1 LAST PART_NUMBER CH4104K1B00
J 0
(-2650 4075);
DISPLAY 0.489362 (-2650 4075);
PAINT SKYBLUE (-2650 4075);
FORCEPROP 1 LAST VOLTAGE 25V
J 0
(-2650 4275);
DISPLAY 0.489362 (-2650 4275);
PAINT SKYBLUE (-2650 4275);
FORCEPROP 1 LAST PACK_TYPE 0402
J 0
(-2650 4125);
DISPLAY 0.489362 (-2650 4125);
PAINT SKYBLUE (-2650 4125);
FORCEPROP 2 LAST CDS_LIB pure_quanta
J 0
(-2700 4250);
DISPLAY INVISIBLE (-2700 4250);
FORCEPROP 1 LAST PATH I111
J 0
(-2650 4400);
DISPLAY 0.978723 (-2650 4400);
PAINT WHITE (-2650 4400);
DISPLAY INVISIBLE (-2650 4400);
FORCEADD Q_RES..1
(-4575 3550);
FORCEPROP 1 LAST LOCATION PR84
J 0
(-4600 3600);
DISPLAY 0.489362 (-4600 3600);
PAINT SKYBLUE (-4600 3600);
FORCEPROP 0 LAST $SEC 1
J 0
(-4325 3700);
DISPLAY 0.680851 (-4325 3700);
PAINT MONO (-4325 3700);
DISPLAY INVISIBLE (-4325 3700);
FORCEPROP 0 LAST CDS_SEC 1
J 0
(-4325 3700);
DISPLAY 1.021277 (-4325 3700);
DISPLAY INVISIBLE (-4325 3700);
FORCEPROP 1 LASTPIN (-4675 3550) $PN 1
J 0
(-4663 3562);
DISPLAY 0.489362 (-4663 3562);
PAINT MONO (-4663 3562);
FORCEPROP 1 LASTPIN (-4475 3550) $PN 2
J 0
(-4513 3562);
DISPLAY 0.489362 (-4513 3562);
PAINT MONO (-4513 3562);
FORCEPROP 1 LAST PART_NUMBER CS00002JB38
J 0
(-4850 3500);
DISPLAY 0.489362 (-4850 3500);
PAINT SKYBLUE (-4850 3500);
FORCEPROP 1 LAST TOLERANCE 5%
J 0
(-4725 3600);
DISPLAY 0.489362 (-4725 3600);
PAINT SKYBLUE (-4725 3600);
FORCEPROP 1 LAST PACK_TYPE 0402LF
J 0
(-4475 3500);
DISPLAY 0.489362 (-4475 3500);
PAINT SKYBLUE (-4475 3500);
FORCEPROP 1 LAST MATERIAL CHIP
J 0
(-4425 3575);
DISPLAY 0.489362 (-4425 3575);
PAINT SKYBLUE (-4425 3575);
FORCEPROP 1 LAST WATTAGE 1/16W
J 2
(-4325 3625);
DISPLAY 0.489362 (-4325 3625);
PAINT SKYBLUE (-4325 3625);
FORCEPROP 1 LAST VALUE 0
J 2
(-4750 3600);
DISPLAY 0.489362 (-4750 3600);
PAINT SKYBLUE (-4750 3600);
FORCEPROP 2 LAST CDS_LIB pure_quanta
J 0
(-4575 3550);
DISPLAY INVISIBLE (-4575 3550);
FORCEPROP 1 LAST PATH I112
J 0
(-4625 3700);
DISPLAY 0.978723 (-4625 3700);
PAINT WHITE (-4625 3700);
DISPLAY INVISIBLE (-4625 3700);
FORCEADD Q_RES..1
(-4650 600);
FORCEPROP 1 LAST LOCATION PR83
J 0
(-4700 650);
DISPLAY 0.489362 (-4700 650);
PAINT SKYBLUE (-4700 650);
FORCEPROP 0 LAST $SEC 1
J 0
(-4400 750);
DISPLAY 0.680851 (-4400 750);
PAINT MONO (-4400 750);
DISPLAY INVISIBLE (-4400 750);
FORCEPROP 0 LAST CDS_SEC 1
J 0
(-4400 750);
DISPLAY 1.021277 (-4400 750);
DISPLAY INVISIBLE (-4400 750);
FORCEPROP 1 LASTPIN (-4750 600) $PN 1
J 0
(-4738 612);
DISPLAY 0.489362 (-4738 612);
PAINT MONO (-4738 612);
FORCEPROP 1 LASTPIN (-4550 600) $PN 2
J 0
(-4588 612);
DISPLAY 0.489362 (-4588 612);
PAINT MONO (-4588 612);
FORCEPROP 1 LAST WATTAGE 1/16W
J 2
(-4400 675);
DISPLAY 0.489362 (-4400 675);
PAINT SKYBLUE (-4400 675);
FORCEPROP 1 LAST MATERIAL CHIP
J 0
(-4500 625);
DISPLAY 0.489362 (-4500 625);
PAINT SKYBLUE (-4500 625);
FORCEPROP 1 LAST TOLERANCE 5%
J 0
(-4825 650);
DISPLAY 0.489362 (-4825 650);
PAINT SKYBLUE (-4825 650);
FORCEPROP 1 LAST VALUE 0
J 2
(-4875 650);
DISPLAY 0.489362 (-4875 650);
PAINT SKYBLUE (-4875 650);
FORCEPROP 1 LAST PART_NUMBER CS00002JB38
J 0
(-4950 550);
DISPLAY 0.489362 (-4950 550);
PAINT SKYBLUE (-4950 550);
FORCEPROP 1 LAST PACK_TYPE 0402LF
J 0
(-4550 550);
DISPLAY 0.489362 (-4550 550);
PAINT SKYBLUE (-4550 550);
FORCEPROP 2 LAST CDS_LIB pure_quanta
J 0
(-4650 600);
DISPLAY INVISIBLE (-4650 600);
FORCEPROP 1 LAST PATH I124
J 0
(-4700 750);
DISPLAY 0.978723 (-4700 750);
PAINT WHITE (-4700 750);
DISPLAY INVISIBLE (-4700 750);
FORCEADD UNIVERSAL_GND..1
(-2025 950);
FORCEPROP 3 LASTPIN (-2025 1000) SIG_NAME GND\g
J 0
(-2015 1010);
DISPLAY 0.659574 (-2015 1010);
PAINT MONO (-2015 1010);
DISPLAY INVISIBLE (-2015 1010);
FORCEPROP 2 LAST CDS_LIB pure_quanta_power
J 0
(-2025 950);
PAINT MONO (-2025 950);
DISPLAY INVISIBLE (-2025 950);
FORCEPROP 1 LAST PATH I125
J 0
(-1950 950);
DISPLAY 0.872340 (-1950 950);
PAINT AQUA (-1950 950);
DISPLAY INVISIBLE (-1950 950);
FORCEPROP 1 LAST HDL_POWER GND
J 1
(-2000 875);
DISPLAY 0.872340 (-2000 875);
PAINT GREEN (-2000 875);
DISPLAY INVISIBLE (-2000 875);
FORCEADD VCC_CORE..1
(-2025 1600);
FORCEPROP 3 LASTPIN (-2025 1550) SIG_NAME PVDDCR_CPU1_P0\g
J 0
(-2015 1560);
DISPLAY 0.659574 (-2015 1560);
PAINT MONO (-2015 1560);
DISPLAY INVISIBLE (-2015 1560);
FORCEPROP 1 LAST HDL_POWER PVDDCR_CPU1_P0
J 1
(-2025 1650);
DISPLAY 0.489362 (-2025 1650);
PAINT GREEN (-2025 1650);
FORCEPROP 2 LAST CDS_LIB pure_quanta_power
J 0
(-2025 1600);
DISPLAY INVISIBLE (-2025 1600);
FORCEPROP 1 LAST PATH I126
J 0
(-1975 1625);
DISPLAY 0.872340 (-1975 1625);
PAINT AQUA (-1975 1625);
DISPLAY INVISIBLE (-1975 1625);
FORCEADD Q_CAP..1
(-2025 1300);
FORCEPROP 1 LAST LOCATION PC108_2
J 0
(-1975 1425);
DISPLAY 0.489362 (-1975 1425);
PAINT SKYBLUE (-1975 1425);
FORCEPROP 0 LAST $SEC 1
J 0
(-1975 1475);
DISPLAY 0.680851 (-1975 1475);
PAINT MONO (-1975 1475);
DISPLAY INVISIBLE (-1975 1475);
FORCEPROP 0 LAST CDS_SEC 1
J 0
(-1975 1475);
DISPLAY 1.021277 (-1975 1475);
DISPLAY INVISIBLE (-1975 1475);
FORCEPROP 1 LASTPIN (-2025 1400) $PN 1
J 0
(-2015 1380);
DISPLAY 0.489362 (-2015 1380);
PAINT MONO (-2015 1380);
FORCEPROP 1 LASTPIN (-2025 1200) $PN 2
J 0
(-2015 1180);
DISPLAY 0.489362 (-2015 1180);
PAINT MONO (-2015 1180);
FORCEPROP 1 LAST MATERIAL X6S
J 0
(-1975 1225);
DISPLAY 0.489362 (-1975 1225);
PAINT SKYBLUE (-1975 1225);
FORCEPROP 1 LAST TOLERANCE 20%
J 0
(-1975 1275);
DISPLAY 0.489362 (-1975 1275);
PAINT SKYBLUE (-1975 1275);
FORCEPROP 1 LAST VALUE 22UF
J 0
(-1975 1375);
DISPLAY 0.489362 (-1975 1375);
PAINT SKYBLUE (-1975 1375);
FORCEPROP 1 LAST PART_NUMBER TMP_QCH622KMEA01
J 0
(-1975 1125);
DISPLAY 0.489362 (-1975 1125);
PAINT SKYBLUE (-1975 1125);
FORCEPROP 1 LAST VOLTAGE 4V
J 0
(-1975 1325);
DISPLAY 0.489362 (-1975 1325);
PAINT SKYBLUE (-1975 1325);
FORCEPROP 1 LAST PACK_TYPE 0805
J 0
(-1975 1175);
DISPLAY 0.489362 (-1975 1175);
PAINT SKYBLUE (-1975 1175);
FORCEPROP 2 LAST CDS_LIB pure_quanta
J 0
(-2025 1300);
DISPLAY INVISIBLE (-2025 1300);
FORCEPROP 1 LAST PATH I127
J 0
(-1975 1450);
DISPLAY 0.978723 (-1975 1450);
PAINT WHITE (-1975 1450);
DISPLAY INVISIBLE (-1975 1450);
FORCEADD Q_CAP..1
(-2450 1300);
FORCEPROP 1 LAST LOCATION PC106_2
J 0
(-2400 1425);
DISPLAY 0.489362 (-2400 1425);
PAINT SKYBLUE (-2400 1425);
FORCEPROP 0 LAST $SEC 1
J 0
(-2400 1475);
DISPLAY 0.680851 (-2400 1475);
PAINT MONO (-2400 1475);
DISPLAY INVISIBLE (-2400 1475);
FORCEPROP 0 LAST CDS_SEC 1
J 0
(-2400 1475);
DISPLAY 1.021277 (-2400 1475);
DISPLAY INVISIBLE (-2400 1475);
FORCEPROP 1 LASTPIN (-2450 1400) $PN 1
J 0
(-2440 1380);
DISPLAY 0.489362 (-2440 1380);
PAINT MONO (-2440 1380);
FORCEPROP 1 LASTPIN (-2450 1200) $PN 2
J 0
(-2440 1180);
DISPLAY 0.489362 (-2440 1180);
PAINT MONO (-2440 1180);
FORCEPROP 1 LAST MATERIAL X6S
J 0
(-2400 1225);
DISPLAY 0.489362 (-2400 1225);
PAINT SKYBLUE (-2400 1225);
FORCEPROP 1 LAST TOLERANCE 20%
J 0
(-2400 1275);
DISPLAY 0.489362 (-2400 1275);
PAINT SKYBLUE (-2400 1275);
FORCEPROP 1 LAST VALUE 22UF
J 0
(-2400 1375);
DISPLAY 0.489362 (-2400 1375);
PAINT SKYBLUE (-2400 1375);
FORCEPROP 1 LAST PART_NUMBER TMP_QCH622KMEA01
J 0
(-2400 1125);
DISPLAY 0.489362 (-2400 1125);
PAINT SKYBLUE (-2400 1125);
FORCEPROP 1 LAST VOLTAGE 4V
J 0
(-2400 1325);
DISPLAY 0.489362 (-2400 1325);
PAINT SKYBLUE (-2400 1325);
FORCEPROP 1 LAST PACK_TYPE 0805
J 0
(-2400 1175);
DISPLAY 0.489362 (-2400 1175);
PAINT SKYBLUE (-2400 1175);
FORCEPROP 2 LAST CDS_LIB pure_quanta
J 0
(-2450 1300);
DISPLAY INVISIBLE (-2450 1300);
FORCEPROP 1 LAST PATH I128
J 0
(-2400 1450);
DISPLAY 0.978723 (-2400 1450);
PAINT WHITE (-2400 1450);
DISPLAY INVISIBLE (-2400 1450);
FORCEADD UNIVERSAL_GND..1
(-8850 3725);
FORCEPROP 3 LASTPIN (-8850 3775) SIG_NAME GND\g
J 0
(-8840 3785);
DISPLAY 0.659574 (-8840 3785);
PAINT MONO (-8840 3785);
DISPLAY INVISIBLE (-8840 3785);
FORCEPROP 2 LAST CDS_LIB pure_quanta_power
J 0
(-8850 3725);
PAINT MONO (-8850 3725);
DISPLAY INVISIBLE (-8850 3725);
FORCEPROP 1 LAST PATH I13
J 0
(-8775 3725);
DISPLAY 0.872340 (-8775 3725);
PAINT AQUA (-8775 3725);
DISPLAY INVISIBLE (-8775 3725);
FORCEPROP 1 LAST HDL_POWER GND
J 1
(-8825 3650);
DISPLAY 0.872340 (-8825 3650);
PAINT GREEN (-8825 3650);
DISPLAY INVISIBLE (-8825 3650);
FORCEADD Q_INDUCTOR4P_14..1
(-3875 1375);
FORCEPROP 1 LAST LOCATION PL11
J 0
(-4100 1630);
DISPLAY 0.489362 (-4100 1630);
PAINT SKYBLUE (-4100 1630);
FORCEPROP 0 LAST $SEC 1
J 0
(-4100 1675);
DISPLAY 0.680851 (-4100 1675);
PAINT MONO (-4100 1675);
DISPLAY INVISIBLE (-4100 1675);
FORCEPROP 0 LAST CDS_SEC 1
J 0
(-4100 1675);
DISPLAY 1.021277 (-4100 1675);
DISPLAY INVISIBLE (-4100 1675);
FORCEPROP 0 LASTPIN (-4275 1500) $PN 1
J 2
(-4285 1510);
DISPLAY 0.489362 (-4285 1510);
PAINT MONO (-4285 1510);
FORCEPROP 0 LASTPIN (-4275 1250) $PN 2
J 2
(-4285 1260);
DISPLAY 0.489362 (-4285 1260);
PAINT MONO (-4285 1260);
FORCEPROP 0 LASTPIN (-3475 1250) $PN 3
J 0
(-3465 1260);
DISPLAY 0.489362 (-3465 1260);
PAINT MONO (-3465 1260);
FORCEPROP 0 LASTPIN (-3475 1500) $PN 4
J 0
(-3465 1510);
DISPLAY 0.489362 (-3465 1510);
PAINT MONO (-3465 1510);
FORCEPROP 1 LAST MATERIAL IND
J 0
(-4075 1550);
DISPLAY 0.489362 (-4075 1550);
PAINT SKYBLUE (-4075 1550);
FORCEPROP 1 LAST PART_NUMBER CV+15^0TZ04
J 0
(-3825 1550);
DISPLAY 0.489362 (-3825 1550);
PAINT SKYBLUE (-3825 1550);
FORCEPROP 2 LAST PART_TYPE SMLF
J 0
(-3950 1125);
DISPLAY 1.021277 (-3950 1125);
FORCEPROP 2 LAST VALUE 150NH
J 0
(-3975 1550);
DISPLAY 0.489362 (-3975 1550);
PAINT SKYBLUE (-3975 1550);
FORCEPROP 1 LAST NEEDS_NO_SIZE TRUE
J 0
(-3875 1375);
DISPLAY 0.468085 (-3875 1375);
PAINT GREEN (-3875 1375);
DISPLAY INVISIBLE (-3875 1375);
FORCEPROP 2 LAST CDS_LIB pure_quanta
J 0
(-3875 1375);
DISPLAY INVISIBLE (-3875 1375);
FORCEPROP 1 LAST PATH I137
J 0
(-3675 1530);
DISPLAY 0.723404 (-3675 1530);
PAINT GREEN (-3675 1530);
DISPLAY INVISIBLE (-3675 1530);
FORCEADD Q_INDUCTOR4P_14..1
(-4175 4325);
FORCEPROP 1 LAST LOCATION PL10
J 0
(-4400 4580);
DISPLAY 0.489362 (-4400 4580);
PAINT SKYBLUE (-4400 4580);
FORCEPROP 0 LAST $SEC 1
J 0
(-4400 4625);
DISPLAY 0.680851 (-4400 4625);
PAINT MONO (-4400 4625);
DISPLAY INVISIBLE (-4400 4625);
FORCEPROP 0 LAST CDS_SEC 1
J 0
(-4400 4625);
DISPLAY 1.021277 (-4400 4625);
DISPLAY INVISIBLE (-4400 4625);
FORCEPROP 0 LASTPIN (-4575 4450) $PN 1
J 2
(-4585 4460);
DISPLAY 0.489362 (-4585 4460);
PAINT MONO (-4585 4460);
FORCEPROP 0 LASTPIN (-4575 4200) $PN 2
J 2
(-4585 4210);
DISPLAY 0.489362 (-4585 4210);
PAINT MONO (-4585 4210);
FORCEPROP 0 LASTPIN (-3775 4200) $PN 3
J 0
(-3765 4210);
DISPLAY 0.489362 (-3765 4210);
PAINT MONO (-3765 4210);
FORCEPROP 0 LASTPIN (-3775 4450) $PN 4
J 0
(-3765 4460);
DISPLAY 0.489362 (-3765 4460);
PAINT MONO (-3765 4460);
FORCEPROP 2 LAST PART_TYPE SMLF
J 0
(-4250 4075);
DISPLAY 1.021277 (-4250 4075);
FORCEPROP 2 LAST VALUE 150NH
J 0
(-4275 4500);
DISPLAY 0.489362 (-4275 4500);
PAINT SKYBLUE (-4275 4500);
FORCEPROP 1 LAST PART_NUMBER CV+15^0TZ04
J 0
(-4125 4500);
DISPLAY 0.489362 (-4125 4500);
PAINT SKYBLUE (-4125 4500);
FORCEPROP 1 LAST MATERIAL IND
J 0
(-4375 4500);
DISPLAY 0.489362 (-4375 4500);
PAINT SKYBLUE (-4375 4500);
FORCEPROP 1 LAST NEEDS_NO_SIZE TRUE
J 0
(-4175 4325);
DISPLAY 0.468085 (-4175 4325);
PAINT GREEN (-4175 4325);
DISPLAY INVISIBLE (-4175 4325);
FORCEPROP 2 LAST CDS_LIB pure_quanta
J 0
(-4175 4325);
DISPLAY INVISIBLE (-4175 4325);
FORCEPROP 1 LAST PATH I138
J 0
(-3975 4480);
DISPLAY 0.723404 (-3975 4480);
PAINT GREEN (-3975 4480);
DISPLAY INVISIBLE (-3975 4480);
FORCEADD Q_CAP..1
(-9475 1175);
FORCEPROP 1 LAST LOCATION PC83_2
J 0
(-9425 1225);
DISPLAY 0.489362 (-9425 1225);
PAINT SKYBLUE (-9425 1225);
FORCEPROP 0 LAST $SEC 1
J 0
(-9425 1300);
DISPLAY 0.680851 (-9425 1300);
PAINT MONO (-9425 1300);
DISPLAY INVISIBLE (-9425 1300);
FORCEPROP 0 LAST CDS_SEC 1
J 0
(-9225 1225);
DISPLAY 1.021277 (-9225 1225);
DISPLAY INVISIBLE (-9225 1225);
FORCEPROP 1 LASTPIN (-9475 1275) $PN 1
J 0
(-9465 1255);
DISPLAY 0.489362 (-9465 1255);
PAINT MONO (-9465 1255);
FORCEPROP 1 LASTPIN (-9475 1075) $PN 2
J 0
(-9465 1055);
DISPLAY 0.489362 (-9465 1055);
PAINT MONO (-9465 1055);
FORCEPROP 1 LAST MATERIAL X7R
J 0
(-9425 1025);
DISPLAY 0.489362 (-9425 1025);
PAINT SKYBLUE (-9425 1025);
FORCEPROP 1 LAST TOLERANCE 10%
J 0
(-9425 1075);
DISPLAY 0.489362 (-9425 1075);
PAINT SKYBLUE (-9425 1075);
FORCEPROP 1 LAST VALUE 0.1UF
J 0
(-9425 1175);
DISPLAY 0.489362 (-9425 1175);
PAINT SKYBLUE (-9425 1175);
FORCEPROP 1 LAST PART_NUMBER CH4104K1B00
J 0
(-9425 975);
DISPLAY 0.489362 (-9425 975);
PAINT SKYBLUE (-9425 975);
FORCEPROP 1 LAST VOLTAGE 25V
J 0
(-9425 1125);
DISPLAY 0.489362 (-9425 1125);
PAINT SKYBLUE (-9425 1125);
FORCEPROP 1 LAST PACK_TYPE 0402
J 0
(-9425 925);
DISPLAY 0.489362 (-9425 925);
PAINT SKYBLUE (-9425 925);
FORCEPROP 2 LAST CDS_LIB pure_quanta
J 0
(-9475 1175);
DISPLAY INVISIBLE (-9475 1175);
FORCEPROP 1 LAST PATH I139
J 0
(-9425 1325);
DISPLAY 0.978723 (-9425 1325);
PAINT WHITE (-9425 1325);
DISPLAY INVISIBLE (-9425 1325);
FORCEADD Q_RES..2
R 2
(-8850 3950);
FORCEPROP 1 LAST LOCATION PR78
J 2
(-8895 4075);
DISPLAY 0.489362 (-8895 4075);
PAINT SKYBLUE (-8895 4075);
FORCEPROP 0 LAST $SEC 1
J 0
(-8875 4125);
DISPLAY 0.680851 (-8875 4125);
PAINT MONO (-8875 4125);
DISPLAY INVISIBLE (-8875 4125);
FORCEPROP 0 LAST CDS_SEC 1
J 0
(-8875 4125);
DISPLAY 1.021277 (-8875 4125);
DISPLAY INVISIBLE (-8875 4125);
FORCEPROP 1 LASTPIN (-8850 4050) $PN 1
J 2
(-8855 4012);
DISPLAY 0.489362 (-8855 4012);
PAINT MONO (-8855 4012);
FORCEPROP 1 LASTPIN (-8850 3850) $PN 2
J 2
(-8855 3860);
DISPLAY 0.489362 (-8855 3860);
PAINT MONO (-8855 3860);
FORCEPROP 1 LAST WATTAGE 1/16W
J 2
(-8890 3925);
DISPLAY 0.489362 (-8890 3925);
PAINT SKYBLUE (-8890 3925);
FORCEPROP 1 LAST MATERIAL EMPTY
J 2
(-8890 3875);
DISPLAY 0.489362 (-8890 3875);
PAINT RED (-8890 3875);
FORCEPROP 1 LAST TOLERANCE 1%
J 2
(-8895 3975);
DISPLAY 0.489362 (-8895 3975);
PAINT SKYBLUE (-8895 3975);
FORCEPROP 1 LAST VALUE 8.87K
J 2
(-8895 4025);
DISPLAY 0.489362 (-8895 4025);
PAINT SKYBLUE (-8895 4025);
FORCEPROP 1 LAST PART_NUMBER CS28872FB01
J 2
(-8890 3825);
DISPLAY 0.489362 (-8890 3825);
PAINT SKYBLUE (-8890 3825);
FORCEPROP 1 LAST PACK_TYPE 0402LF
J 2
(-8890 3775);
DISPLAY 0.489362 (-8890 3775);
PAINT SKYBLUE (-8890 3775);
FORCEPROP 2 LAST CDS_LIB pure_quanta
J 2
(-8850 3950);
DISPLAY INVISIBLE (-8850 3950);
FORCEPROP 1 LAST PATH I14
J 2
(-8900 4125);
DISPLAY 0.978723 (-8900 4125);
PAINT WHITE (-8900 4125);
DISPLAY INVISIBLE (-8900 4125);
FORCEADD Q_CAP..1
(-9350 4075);
FORCEPROP 1 LAST LOCATION PC84_1
J 0
(-9300 4175);
DISPLAY 0.489362 (-9300 4175);
PAINT SKYBLUE (-9300 4175);
FORCEPROP 0 LAST $SEC 1
J 0
(-9300 4200);
DISPLAY 0.680851 (-9300 4200);
PAINT MONO (-9300 4200);
DISPLAY INVISIBLE (-9300 4200);
FORCEPROP 0 LAST CDS_SEC 1
J 0
(-9100 4125);
DISPLAY 1.021277 (-9100 4125);
DISPLAY INVISIBLE (-9100 4125);
FORCEPROP 1 LASTPIN (-9350 4175) $PN 1
J 0
(-9340 4155);
DISPLAY 0.489362 (-9340 4155);
PAINT MONO (-9340 4155);
FORCEPROP 1 LASTPIN (-9350 3975) $PN 2
J 0
(-9340 3955);
DISPLAY 0.489362 (-9340 3955);
PAINT MONO (-9340 3955);
FORCEPROP 1 LAST PART_NUMBER CH4104K1B00
J 0
(-9300 3925);
DISPLAY 0.489362 (-9300 3925);
PAINT SKYBLUE (-9300 3925);
FORCEPROP 1 LAST MATERIAL X7R
J 0
(-9300 3975);
DISPLAY 0.489362 (-9300 3975);
PAINT SKYBLUE (-9300 3975);
FORCEPROP 1 LAST TOLERANCE 10%
J 0
(-9300 4025);
DISPLAY 0.489362 (-9300 4025);
PAINT SKYBLUE (-9300 4025);
FORCEPROP 1 LAST VALUE 0.1UF
J 0
(-9300 4125);
DISPLAY 0.489362 (-9300 4125);
PAINT SKYBLUE (-9300 4125);
FORCEPROP 1 LAST VOLTAGE 25V
J 0
(-9300 4075);
DISPLAY 0.489362 (-9300 4075);
PAINT SKYBLUE (-9300 4075);
FORCEPROP 1 LAST PACK_TYPE 0402
J 0
(-9300 3875);
DISPLAY 0.489362 (-9300 3875);
PAINT SKYBLUE (-9300 3875);
FORCEPROP 2 LAST CDS_LIB pure_quanta
J 0
(-9350 4075);
DISPLAY INVISIBLE (-9350 4075);
FORCEPROP 1 LAST PATH I140
J 0
(-9300 4225);
DISPLAY 0.978723 (-9300 4225);
PAINT WHITE (-9300 4225);
DISPLAY INVISIBLE (-9300 4225);
FORCEADD Q_CAP..1
(-4950 4675);
FORCEPROP 1 LAST LOCATION PC92
J 0
(-4900 4775);
DISPLAY 0.489362 (-4900 4775);
PAINT SKYBLUE (-4900 4775);
FORCEPROP 0 LAST $SEC 1
J 0
(-4900 4825);
DISPLAY 0.680851 (-4900 4825);
PAINT MONO (-4900 4825);
DISPLAY INVISIBLE (-4900 4825);
FORCEPROP 0 LAST CDS_SEC 1
J 0
(-4900 4825);
DISPLAY 1.021277 (-4900 4825);
DISPLAY INVISIBLE (-4900 4825);
FORCEPROP 1 LASTPIN (-4950 4775) $PN 1
J 0
(-4940 4755);
DISPLAY 0.489362 (-4940 4755);
PAINT MONO (-4940 4755);
FORCEPROP 1 LASTPIN (-4950 4575) $PN 2
J 0
(-4940 4555);
DISPLAY 0.489362 (-4940 4555);
PAINT MONO (-4940 4555);
FORCEPROP 1 LAST TOLERANCE 10%
J 0
(-4900 4625);
DISPLAY 0.489362 (-4900 4625);
PAINT SKYBLUE (-4900 4625);
FORCEPROP 1 LAST MATERIAL X7R
J 0
(-4900 4575);
DISPLAY 0.489362 (-4900 4575);
PAINT SKYBLUE (-4900 4575);
FORCEPROP 1 LAST VALUE 0.22UF
J 0
(-4900 4725);
DISPLAY 0.489362 (-4900 4725);
PAINT SKYBLUE (-4900 4725);
FORCEPROP 1 LAST PART_NUMBER CH4223K1B00
J 0
(-4900 4525);
DISPLAY 0.489362 (-4900 4525);
PAINT SKYBLUE (-4900 4525);
FORCEPROP 1 LAST VOLTAGE 16V
J 0
(-4900 4675);
DISPLAY 0.489362 (-4900 4675);
PAINT SKYBLUE (-4900 4675);
FORCEPROP 1 LAST PACK_TYPE 0402
J 0
(-4900 4475);
DISPLAY 0.489362 (-4900 4475);
PAINT SKYBLUE (-4900 4475);
FORCEPROP 2 LAST CDS_LIB pure_quanta
J 2
(-4950 4675);
DISPLAY INVISIBLE (-4950 4675);
FORCEPROP 1 LAST PATH I141
J 0
(-4900 4825);
DISPLAY 0.978723 (-4900 4825);
PAINT WHITE (-4900 4825);
DISPLAY INVISIBLE (-4900 4825);
FORCEADD Q_RES..1
(-5675 4800);
FORCEPROP 1 LAST LOCATION PR82
J 0
(-5700 4850);
DISPLAY 0.489362 (-5700 4850);
PAINT SKYBLUE (-5700 4850);
FORCEPROP 0 LAST $SEC 1
J 0
(-5800 4950);
DISPLAY 0.680851 (-5800 4950);
PAINT MONO (-5800 4950);
DISPLAY INVISIBLE (-5800 4950);
FORCEPROP 0 LAST CDS_SEC 1
J 0
(-5800 4950);
DISPLAY 1.021277 (-5800 4950);
DISPLAY INVISIBLE (-5800 4950);
FORCEPROP 1 LASTPIN (-5775 4800) $PN 1
J 0
(-5763 4812);
DISPLAY 0.787234 (-5763 4812);
PAINT MONO (-5763 4812);
DISPLAY INVISIBLE (-5763 4812);
FORCEPROP 1 LASTPIN (-5575 4800) $PN 2
J 0
(-5613 4812);
DISPLAY 0.787234 (-5613 4812);
PAINT MONO (-5613 4812);
DISPLAY INVISIBLE (-5613 4812);
FORCEPROP 1 LAST TOLERANCE 1%
J 0
(-5800 4825);
DISPLAY 0.489362 (-5800 4825);
PAINT SKYBLUE (-5800 4825);
FORCEPROP 1 LAST WATTAGE 1/16W
J 2
(-5400 4875);
DISPLAY 0.489362 (-5400 4875);
PAINT SKYBLUE (-5400 4875);
FORCEPROP 1 LAST MATERIAL CHIP
J 0
(-5550 4675);
DISPLAY 0.489362 (-5550 4675);
PAINT SKYBLUE (-5550 4675);
FORCEPROP 1 LAST PACK_TYPE 0402LF
J 0
(-5575 4725);
DISPLAY 0.489362 (-5575 4725);
PAINT SKYBLUE (-5575 4725);
FORCEPROP 1 LAST VALUE 4.7
J 2
(-5750 4875);
DISPLAY 0.489362 (-5750 4875);
PAINT SKYBLUE (-5750 4875);
FORCEPROP 1 LAST PART_NUMBER CS-4702FB19
J 0
(-5975 4725);
DISPLAY 0.489362 (-5975 4725);
PAINT SKYBLUE (-5975 4725);
FORCEPROP 1 LAST PATH I142
J 0
(-5725 4950);
DISPLAY 0.978723 (-5725 4950);
PAINT WHITE (-5725 4950);
DISPLAY INVISIBLE (-5725 4950);
FORCEPROP 2 LAST CDS_LIB pure_quanta
J 0
(-5675 4800);
DISPLAY INVISIBLE (-5675 4800);
FORCEADD Q_CAP..1
(-4900 1725);
FORCEPROP 1 LAST LOCATION PC94
J 0
(-4850 1825);
DISPLAY 0.489362 (-4850 1825);
PAINT SKYBLUE (-4850 1825);
FORCEPROP 0 LAST $SEC 1
J 0
(-4850 1875);
DISPLAY 0.680851 (-4850 1875);
PAINT MONO (-4850 1875);
DISPLAY INVISIBLE (-4850 1875);
FORCEPROP 0 LAST CDS_SEC 1
J 2
(-4850 1850);
DISPLAY 1.021277 (-4850 1850);
DISPLAY INVISIBLE (-4850 1850);
FORCEPROP 1 LASTPIN (-4900 1825) $PN 1
J 0
(-4890 1805);
DISPLAY 0.489362 (-4890 1805);
PAINT MONO (-4890 1805);
FORCEPROP 1 LASTPIN (-4900 1625) $PN 2
J 0
(-4890 1605);
DISPLAY 0.489362 (-4890 1605);
PAINT MONO (-4890 1605);
FORCEPROP 1 LAST MATERIAL X7R
J 0
(-4850 1625);
DISPLAY 0.489362 (-4850 1625);
PAINT SKYBLUE (-4850 1625);
FORCEPROP 1 LAST TOLERANCE 10%
J 0
(-4850 1675);
DISPLAY 0.489362 (-4850 1675);
PAINT SKYBLUE (-4850 1675);
FORCEPROP 1 LAST VALUE 0.22UF
J 0
(-4850 1775);
DISPLAY 0.489362 (-4850 1775);
PAINT SKYBLUE (-4850 1775);
FORCEPROP 1 LAST PART_NUMBER CH4223K1B00
J 0
(-4850 1575);
DISPLAY 0.489362 (-4850 1575);
PAINT SKYBLUE (-4850 1575);
FORCEPROP 1 LAST VOLTAGE 16V
J 0
(-4850 1725);
DISPLAY 0.489362 (-4850 1725);
PAINT SKYBLUE (-4850 1725);
FORCEPROP 1 LAST PACK_TYPE 0402
J 0
(-4850 1525);
DISPLAY 0.489362 (-4850 1525);
PAINT SKYBLUE (-4850 1525);
FORCEPROP 2 LAST CDS_LIB pure_quanta
J 2
(-4900 1725);
DISPLAY INVISIBLE (-4900 1725);
FORCEPROP 1 LAST PATH I143
J 0
(-4850 1875);
DISPLAY 0.978723 (-4850 1875);
PAINT WHITE (-4850 1875);
DISPLAY INVISIBLE (-4850 1875);
FORCEADD Q_RES..1
(-5700 1850);
FORCEPROP 1 LAST LOCATION PR81
J 0
(-5925 1925);
DISPLAY 0.489362 (-5925 1925);
PAINT SKYBLUE (-5925 1925);
FORCEPROP 0 LAST $SEC 1
J 0
(-5425 1950);
DISPLAY 0.680851 (-5425 1950);
PAINT MONO (-5425 1950);
DISPLAY INVISIBLE (-5425 1950);
FORCEPROP 0 LAST CDS_SEC 1
J 0
(-5425 1950);
DISPLAY 1.021277 (-5425 1950);
DISPLAY INVISIBLE (-5425 1950);
FORCEPROP 1 LASTPIN (-5800 1850) $PN 1
J 0
(-5788 1862);
DISPLAY 0.787234 (-5788 1862);
PAINT MONO (-5788 1862);
DISPLAY INVISIBLE (-5788 1862);
FORCEPROP 1 LASTPIN (-5600 1850) $PN 2
J 0
(-5638 1862);
DISPLAY 0.787234 (-5638 1862);
PAINT MONO (-5638 1862);
DISPLAY INVISIBLE (-5638 1862);
FORCEPROP 1 LAST TOLERANCE 1%
J 0
(-5700 1925);
DISPLAY 0.489362 (-5700 1925);
PAINT SKYBLUE (-5700 1925);
FORCEPROP 1 LAST MATERIAL CHIP
J 0
(-5850 1775);
DISPLAY 0.489362 (-5850 1775);
PAINT SKYBLUE (-5850 1775);
FORCEPROP 1 LAST WATTAGE 1/16W
J 2
(-5425 1925);
DISPLAY 0.489362 (-5425 1925);
PAINT SKYBLUE (-5425 1925);
FORCEPROP 1 LAST PACK_TYPE 0402LF
J 0
(-5300 1775);
DISPLAY 0.489362 (-5300 1775);
PAINT SKYBLUE (-5300 1775);
FORCEPROP 1 LAST VALUE 4.7
J 2
(-5750 1925);
DISPLAY 0.489362 (-5750 1925);
PAINT SKYBLUE (-5750 1925);
FORCEPROP 1 LAST PART_NUMBER CS-4702FB19
J 0
(-5675 1775);
DISPLAY 0.489362 (-5675 1775);
PAINT SKYBLUE (-5675 1775);
FORCEPROP 1 LAST PATH I144
J 0
(-5750 2000);
DISPLAY 0.978723 (-5750 2000);
PAINT WHITE (-5750 2000);
DISPLAY INVISIBLE (-5750 2000);
FORCEPROP 2 LAST CDS_LIB pure_quanta
J 0
(-5700 1850);
DISPLAY INVISIBLE (-5700 1850);
FORCEADD OFFPAGE..5
(-8325 1500);
FORCEPROP 2 LAST $XR0 176 
J 0
(-8610 1500);
DISPLAY 0.638298 (-8610 1500);
PAINT MONO (-8610 1500);
FORCEPROP 1 LAST COMMENT_BODY TRUE
J 0
(-8225 1425);
DISPLAY 0.872340 (-8225 1425);
PAINT GREEN (-8225 1425);
DISPLAY INVISIBLE (-8225 1425);
FORCEPROP 2 LAST CDS_LIB standard
J 0
(-8325 1500);
DISPLAY INVISIBLE (-8325 1500);
FORCEPROP 2 LAST PATH I145
J 0
(-8275 1575);
DISPLAY 1.021277 (-8275 1575);
DISPLAY INVISIBLE (-8275 1575);
FORCEPROP 1 LAST OFFPAGE TRUE
J 0
(-8000 1375);
DISPLAY 0.872340 (-8000 1375);
PAINT GREEN (-8000 1375);
DISPLAY INVISIBLE (-8000 1375);
FORCEADD OFFPAGE..6
(-4875 1250);
FORCEPROP 2 LAST $XR0 177 
J 0
(-5155 1250);
DISPLAY 0.638298 (-5155 1250);
PAINT MONO (-5155 1250);
FORCEPROP 2 LAST CDS_LIB standard
J 0
(-4875 1250);
DISPLAY INVISIBLE (-4875 1250);
FORCEPROP 1 LAST COMMENT_BODY TRUE
J 0
(-4775 1175);
DISPLAY 0.872340 (-4775 1175);
PAINT GREEN (-4775 1175);
DISPLAY INVISIBLE (-4775 1175);
FORCEPROP 2 LAST PATH I146
J 0
(-4825 1325);
DISPLAY 1.021277 (-4825 1325);
DISPLAY INVISIBLE (-4825 1325);
FORCEPROP 1 LAST OFFPAGE TRUE
J 0
(-4550 1125);
DISPLAY 0.872340 (-4550 1125);
PAINT GREEN (-4550 1125);
DISPLAY INVISIBLE (-4550 1125);
FORCEADD OFFPAGE..6
R 2
(-3275 4200);
FORCEPROP 2 LAST $XR0 177 
J 0
(-3061 4200);
DISPLAY 0.638298 (-3061 4200);
PAINT MONO (-3061 4200);
FORCEPROP 1 LAST OFFPAGE TRUE
J 2
(-3600 4075);
DISPLAY 0.872340 (-3600 4075);
PAINT GREEN (-3600 4075);
DISPLAY INVISIBLE (-3600 4075);
FORCEPROP 1 LAST COMMENT_BODY TRUE
J 2
(-3375 4125);
DISPLAY 0.872340 (-3375 4125);
PAINT GREEN (-3375 4125);
DISPLAY INVISIBLE (-3375 4125);
FORCEPROP 2 LAST CDS_LIB standard
J 2
(-3275 4200);
DISPLAY INVISIBLE (-3275 4200);
FORCEPROP 2 LAST PATH I147
J 2
(-3325 4275);
DISPLAY 1.021277 (-3325 4275);
DISPLAY INVISIBLE (-3325 4275);
FORCEADD Q_CAPP..1
(-3075 3000);
FORCEPROP 1 LAST LOCATION PC97
J 0
(-3025 3100);
DISPLAY 0.489362 (-3025 3100);
PAINT SKYBLUE (-3025 3100);
FORCEPROP 0 LAST $SEC 1
J 0
(-3025 3150);
DISPLAY 0.680851 (-3025 3150);
PAINT MONO (-3025 3150);
DISPLAY INVISIBLE (-3025 3150);
FORCEPROP 0 LAST CDS_SEC 1
J 0
(-3025 3150);
DISPLAY 1.021277 (-3025 3150);
DISPLAY INVISIBLE (-3025 3150);
FORCEPROP 1 LASTPIN (-3075 3100) $PN 1
J 0
(-3065 3085);
DISPLAY 0.489362 (-3065 3085);
PAINT MONO (-3065 3085);
FORCEPROP 1 LASTPIN (-3075 2900) $PN 2
J 0
(-3065 2885);
DISPLAY 0.489362 (-3065 2885);
PAINT MONO (-3065 2885);
FORCEPROP 1 LAST VALUE 220UF
J 0
(-3025 3050);
DISPLAY 0.489362 (-3025 3050);
PAINT SKYBLUE (-3025 3050);
FORCEPROP 1 LAST VOLTAGE 4V
J 0
(-3025 2950);
DISPLAY 0.489362 (-3025 2950);
PAINT SKYBLUE (-3025 2950);
FORCEPROP 1 LAST TOLERANCE 20%
J 0
(-3025 3000);
DISPLAY 0.489362 (-3025 3000);
PAINT SKYBLUE (-3025 3000);
FORCEPROP 1 LAST MATERIAL SPCAP
J 0
(-3025 2900);
DISPLAY 0.489362 (-3025 2900);
PAINT SKYBLUE (-3025 2900);
FORCEPROP 1 LAST PART_NUMBER CH122KM8801
J 0
(-3025 2800);
DISPLAY 0.489362 (-3025 2800);
PAINT SKYBLUE (-3025 2800);
FORCEPROP 1 LAST PACK_TYPE SMLF
J 0
(-3025 2850);
DISPLAY 0.489362 (-3025 2850);
PAINT SKYBLUE (-3025 2850);
FORCEPROP 1 LAST PATH I148
J 0
(-3025 3150);
DISPLAY 0.978723 (-3025 3150);
DISPLAY INVISIBLE (-3025 3150);
FORCEPROP 2 LAST CDS_LIB pure_quanta
J 0
(-3075 3000);
DISPLAY INVISIBLE (-3075 3000);
FORCEADD UNIVERSAL_GND..1
(-2125 2625);
FORCEPROP 3 LASTPIN (-2125 2675) SIG_NAME GND\g
J 0
(-2115 2685);
DISPLAY 0.659574 (-2115 2685);
PAINT MONO (-2115 2685);
DISPLAY INVISIBLE (-2115 2685);
FORCEPROP 2 LAST CDS_LIB pure_quanta_power
J 0
(-2125 2625);
DISPLAY INVISIBLE (-2125 2625);
FORCEPROP 1 LAST PATH I149
J 0
(-2050 2625);
DISPLAY 0.872340 (-2050 2625);
PAINT AQUA (-2050 2625);
DISPLAY INVISIBLE (-2050 2625);
FORCEPROP 1 LAST HDL_POWER GND
J 1
(-2100 2550);
DISPLAY 0.872340 (-2100 2550);
PAINT GREEN (-2100 2550);
DISPLAY INVISIBLE (-2100 2550);
FORCEADD OFFPAGE..1
(-8275 3850);
FORCEPROP 2 LAST $XR0 176 
J 0
(-8527 3850);
DISPLAY 0.638298 (-8527 3850);
PAINT MONO (-8527 3850);
FORCEPROP 2 LAST PATH I15
J 0
(-8525 3900);
DISPLAY 1.021277 (-8525 3900);
DISPLAY INVISIBLE (-8525 3900);
FORCEPROP 2 LAST CDS_LIB standard
J 0
(-8275 3850);
DISPLAY INVISIBLE (-8275 3850);
FORCEPROP 1 LAST COMMENT_BODY TRUE
J 0
(-8150 3750);
DISPLAY 0.872340 (-8150 3750);
PAINT GREEN (-8150 3750);
DISPLAY INVISIBLE (-8150 3750);
FORCEPROP 1 LAST OFFPAGE TRUE
J 0
(-7950 3725);
DISPLAY 0.872340 (-7950 3725);
PAINT GREEN (-7950 3725);
DISPLAY INVISIBLE (-7950 3725);
FORCEADD Q_CAPP..1
(-2750 3000);
FORCEPROP 1 LAST LOCATION PC98
J 0
(-2700 3100);
DISPLAY 0.489362 (-2700 3100);
PAINT SKYBLUE (-2700 3100);
FORCEPROP 0 LAST $SEC 1
J 0
(-2700 3150);
DISPLAY 0.680851 (-2700 3150);
PAINT MONO (-2700 3150);
DISPLAY INVISIBLE (-2700 3150);
FORCEPROP 0 LAST CDS_SEC 1
J 0
(-2700 3150);
DISPLAY 1.021277 (-2700 3150);
DISPLAY INVISIBLE (-2700 3150);
FORCEPROP 1 LASTPIN (-2750 3100) $PN 1
J 0
(-2740 3085);
DISPLAY 0.489362 (-2740 3085);
PAINT MONO (-2740 3085);
FORCEPROP 1 LASTPIN (-2750 2900) $PN 2
J 0
(-2740 2885);
DISPLAY 0.489362 (-2740 2885);
PAINT MONO (-2740 2885);
FORCEPROP 1 LAST VALUE 220UF
J 0
(-2700 3050);
DISPLAY 0.489362 (-2700 3050);
PAINT SKYBLUE (-2700 3050);
FORCEPROP 1 LAST TOLERANCE 20%
J 0
(-2700 3000);
DISPLAY 0.489362 (-2700 3000);
PAINT SKYBLUE (-2700 3000);
FORCEPROP 1 LAST VOLTAGE 4V
J 0
(-2700 2950);
DISPLAY 0.489362 (-2700 2950);
PAINT SKYBLUE (-2700 2950);
FORCEPROP 1 LAST MATERIAL SPCAP
J 0
(-2700 2900);
DISPLAY 0.489362 (-2700 2900);
PAINT SKYBLUE (-2700 2900);
FORCEPROP 1 LAST PART_NUMBER CH122KM8801
J 0
(-2700 2800);
DISPLAY 0.489362 (-2700 2800);
PAINT SKYBLUE (-2700 2800);
FORCEPROP 1 LAST PACK_TYPE SMLF
J 0
(-2700 2850);
DISPLAY 0.489362 (-2700 2850);
PAINT SKYBLUE (-2700 2850);
FORCEPROP 1 LAST PATH I150
J 0
(-2700 3150);
DISPLAY 0.978723 (-2700 3150);
DISPLAY INVISIBLE (-2700 3150);
FORCEPROP 2 LAST CDS_LIB pure_quanta
J 0
(-2750 3000);
DISPLAY INVISIBLE (-2750 3000);
FORCEADD Q_CAPP..1
(-2425 3000);
FORCEPROP 1 LAST LOCATION PC100
J 0
(-2375 3100);
DISPLAY 0.489362 (-2375 3100);
PAINT SKYBLUE (-2375 3100);
FORCEPROP 0 LAST $SEC 1
J 0
(-2375 3150);
DISPLAY 0.680851 (-2375 3150);
PAINT MONO (-2375 3150);
DISPLAY INVISIBLE (-2375 3150);
FORCEPROP 0 LAST CDS_SEC 1
J 0
(-2375 3150);
DISPLAY 1.021277 (-2375 3150);
DISPLAY INVISIBLE (-2375 3150);
FORCEPROP 1 LASTPIN (-2425 3100) $PN 1
J 0
(-2415 3085);
DISPLAY 0.489362 (-2415 3085);
PAINT MONO (-2415 3085);
FORCEPROP 1 LASTPIN (-2425 2900) $PN 2
J 0
(-2415 2885);
DISPLAY 0.489362 (-2415 2885);
PAINT MONO (-2415 2885);
FORCEPROP 1 LAST PACK_TYPE SMLF
J 0
(-2375 2850);
DISPLAY 0.489362 (-2375 2850);
PAINT SKYBLUE (-2375 2850);
FORCEPROP 1 LAST VOLTAGE 4V
J 0
(-2375 2950);
DISPLAY 0.489362 (-2375 2950);
PAINT SKYBLUE (-2375 2950);
FORCEPROP 1 LAST VALUE 220UF
J 0
(-2375 3050);
DISPLAY 0.489362 (-2375 3050);
PAINT SKYBLUE (-2375 3050);
FORCEPROP 1 LAST TOLERANCE 20%
J 0
(-2375 3000);
DISPLAY 0.489362 (-2375 3000);
PAINT SKYBLUE (-2375 3000);
FORCEPROP 1 LAST MATERIAL SPCAP
J 0
(-2375 2900);
DISPLAY 0.489362 (-2375 2900);
PAINT SKYBLUE (-2375 2900);
FORCEPROP 1 LAST PART_NUMBER CH122KM8801
J 0
(-2375 2800);
DISPLAY 0.489362 (-2375 2800);
PAINT SKYBLUE (-2375 2800);
FORCEPROP 1 LAST PATH I151
J 0
(-2375 3150);
DISPLAY 0.978723 (-2375 3150);
DISPLAY INVISIBLE (-2375 3150);
FORCEPROP 2 LAST CDS_LIB pure_quanta
J 0
(-2425 3000);
DISPLAY INVISIBLE (-2425 3000);
FORCEADD VCC_CORE..1
(-2125 3300);
FORCEPROP 3 LASTPIN (-2125 3250) SIG_NAME PVDDCR_CPU1_P0\g
J 0
(-2115 3260);
DISPLAY 0.659574 (-2115 3260);
PAINT MONO (-2115 3260);
DISPLAY INVISIBLE (-2115 3260);
FORCEPROP 1 LAST HDL_POWER PVDDCR_CPU1_P0
J 1
(-2125 3350);
DISPLAY 0.489362 (-2125 3350);
PAINT GREEN (-2125 3350);
FORCEPROP 2 LAST CDS_LIB pure_quanta_power
J 0
(-2125 3300);
DISPLAY INVISIBLE (-2125 3300);
FORCEPROP 1 LAST PATH I152
J 0
(-2075 3325);
DISPLAY 0.872340 (-2075 3325);
PAINT AQUA (-2075 3325);
DISPLAY INVISIBLE (-2075 3325);
FORCEADD Q_CAPP..1
(-2125 3000);
FORCEPROP 1 LAST LOCATION PC103
J 0
(-2075 3100);
DISPLAY 0.489362 (-2075 3100);
PAINT SKYBLUE (-2075 3100);
FORCEPROP 0 LAST $SEC 1
J 0
(-2075 3150);
DISPLAY 0.680851 (-2075 3150);
PAINT MONO (-2075 3150);
DISPLAY INVISIBLE (-2075 3150);
FORCEPROP 0 LAST CDS_SEC 1
J 0
(-2075 3150);
DISPLAY 1.021277 (-2075 3150);
DISPLAY INVISIBLE (-2075 3150);
FORCEPROP 1 LASTPIN (-2125 3100) $PN 1
J 0
(-2115 3085);
DISPLAY 0.489362 (-2115 3085);
PAINT MONO (-2115 3085);
FORCEPROP 1 LASTPIN (-2125 2900) $PN 2
J 0
(-2115 2885);
DISPLAY 0.489362 (-2115 2885);
PAINT MONO (-2115 2885);
FORCEPROP 1 LAST PACK_TYPE SMLF
J 0
(-2075 2850);
DISPLAY 0.489362 (-2075 2850);
PAINT SKYBLUE (-2075 2850);
FORCEPROP 1 LAST VOLTAGE 4V
J 0
(-2075 2950);
DISPLAY 0.489362 (-2075 2950);
PAINT SKYBLUE (-2075 2950);
FORCEPROP 1 LAST VALUE 220UF
J 0
(-2075 3050);
DISPLAY 0.489362 (-2075 3050);
PAINT SKYBLUE (-2075 3050);
FORCEPROP 1 LAST TOLERANCE 20%
J 0
(-2075 3000);
DISPLAY 0.489362 (-2075 3000);
PAINT SKYBLUE (-2075 3000);
FORCEPROP 1 LAST MATERIAL SPCAP
J 0
(-2075 2900);
DISPLAY 0.489362 (-2075 2900);
PAINT SKYBLUE (-2075 2900);
FORCEPROP 1 LAST PART_NUMBER CH122KM8801
J 0
(-2075 2800);
DISPLAY 0.489362 (-2075 2800);
PAINT SKYBLUE (-2075 2800);
FORCEPROP 1 LAST PATH I153
J 0
(-2075 3150);
DISPLAY 0.978723 (-2075 3150);
DISPLAY INVISIBLE (-2075 3150);
FORCEPROP 2 LAST CDS_LIB pure_quanta
J 0
(-2125 3000);
DISPLAY INVISIBLE (-2125 3000);
FORCEADD Q_CAP..1
(-6150 5350);
FORCEPROP 1 LAST LOCATION PC85_1
J 0
(-6100 5500);
DISPLAY 0.489362 (-6100 5500);
PAINT SKYBLUE (-6100 5500);
FORCEPROP 0 LAST $SEC 1
J 0
(-6100 5500);
DISPLAY 0.680851 (-6100 5500);
PAINT MONO (-6100 5500);
DISPLAY INVISIBLE (-6100 5500);
FORCEPROP 0 LAST CDS_SEC 1
J 0
(-6100 5500);
DISPLAY 1.021277 (-6100 5500);
DISPLAY INVISIBLE (-6100 5500);
FORCEPROP 1 LASTPIN (-6150 5450) $PN 1
J 0
(-6140 5430);
DISPLAY 0.489362 (-6140 5430);
PAINT MONO (-6140 5430);
FORCEPROP 1 LASTPIN (-6150 5250) $PN 2
J 0
(-6140 5230);
DISPLAY 0.489362 (-6140 5230);
PAINT MONO (-6140 5230);
FORCEPROP 1 LAST MATERIAL X7R
J 0
(-6100 5300);
DISPLAY 0.489362 (-6100 5300);
PAINT SKYBLUE (-6100 5300);
FORCEPROP 1 LAST TOLERANCE 10%
J 0
(-6100 5350);
DISPLAY 0.489362 (-6100 5350);
PAINT SKYBLUE (-6100 5350);
FORCEPROP 1 LAST VALUE 0.1UF
J 0
(-6100 5450);
DISPLAY 0.489362 (-6100 5450);
PAINT SKYBLUE (-6100 5450);
FORCEPROP 1 LAST PART_NUMBER CH4104K1B00
J 0
(-6100 5200);
DISPLAY 0.489362 (-6100 5200);
PAINT SKYBLUE (-6100 5200);
FORCEPROP 1 LAST VOLTAGE 25V
J 0
(-6100 5400);
DISPLAY 0.489362 (-6100 5400);
PAINT SKYBLUE (-6100 5400);
FORCEPROP 1 LAST PACK_TYPE 0402
J 0
(-6100 5250);
DISPLAY 0.489362 (-6100 5250);
PAINT SKYBLUE (-6100 5250);
FORCEPROP 2 LAST CDS_LIB pure_quanta
J 0
(-6150 5350);
DISPLAY INVISIBLE (-6150 5350);
FORCEPROP 1 LAST PATH I154
J 0
(-6100 5500);
DISPLAY 0.978723 (-6100 5500);
PAINT WHITE (-6100 5500);
DISPLAY INVISIBLE (-6100 5500);
FORCEADD Q_CAP..1
(-6125 2400);
FORCEPROP 1 LAST LOCATION PC86_2
J 0
(-6075 2550);
DISPLAY 0.489362 (-6075 2550);
PAINT SKYBLUE (-6075 2550);
FORCEPROP 0 LAST $SEC 1
J 0
(-6075 2550);
DISPLAY 0.680851 (-6075 2550);
PAINT MONO (-6075 2550);
DISPLAY INVISIBLE (-6075 2550);
FORCEPROP 0 LAST CDS_SEC 1
J 0
(-6075 2550);
DISPLAY 1.021277 (-6075 2550);
DISPLAY INVISIBLE (-6075 2550);
FORCEPROP 1 LASTPIN (-6125 2500) $PN 1
J 0
(-6115 2480);
DISPLAY 0.489362 (-6115 2480);
PAINT MONO (-6115 2480);
FORCEPROP 1 LASTPIN (-6125 2300) $PN 2
J 0
(-6115 2280);
DISPLAY 0.489362 (-6115 2280);
PAINT MONO (-6115 2280);
FORCEPROP 1 LAST PART_NUMBER CH4104K1B00
J 0
(-6075 2250);
DISPLAY 0.489362 (-6075 2250);
PAINT SKYBLUE (-6075 2250);
FORCEPROP 1 LAST MATERIAL X7R
J 0
(-6075 2350);
DISPLAY 0.489362 (-6075 2350);
PAINT SKYBLUE (-6075 2350);
FORCEPROP 1 LAST TOLERANCE 10%
J 0
(-6075 2400);
DISPLAY 0.489362 (-6075 2400);
PAINT SKYBLUE (-6075 2400);
FORCEPROP 1 LAST VALUE 0.1UF
J 0
(-6075 2500);
DISPLAY 0.489362 (-6075 2500);
PAINT SKYBLUE (-6075 2500);
FORCEPROP 1 LAST VOLTAGE 25V
J 0
(-6075 2450);
DISPLAY 0.489362 (-6075 2450);
PAINT SKYBLUE (-6075 2450);
FORCEPROP 1 LAST PACK_TYPE 0402
J 0
(-6075 2300);
DISPLAY 0.489362 (-6075 2300);
PAINT SKYBLUE (-6075 2300);
FORCEPROP 2 LAST CDS_LIB pure_quanta
J 0
(-6125 2400);
DISPLAY INVISIBLE (-6125 2400);
FORCEPROP 1 LAST PATH I155
J 0
(-6075 2550);
DISPLAY 0.978723 (-6075 2550);
PAINT WHITE (-6075 2550);
DISPLAY INVISIBLE (-6075 2550);
FORCEADD Q_CAP..1
(-8700 4900);
FORCEPROP 1 LAST LOCATION PC79
J 0
(-8650 5000);
DISPLAY 0.489362 (-8650 5000);
PAINT SKYBLUE (-8650 5000);
FORCEPROP 0 LAST $SEC 1
J 0
(-8650 5050);
DISPLAY 0.680851 (-8650 5050);
PAINT MONO (-8650 5050);
DISPLAY INVISIBLE (-8650 5050);
FORCEPROP 0 LAST CDS_SEC 1
J 0
(-8650 5050);
DISPLAY 1.021277 (-8650 5050);
DISPLAY INVISIBLE (-8650 5050);
FORCEPROP 1 LASTPIN (-8700 5000) $PN 1
J 0
(-8690 4980);
DISPLAY 0.489362 (-8690 4980);
PAINT MONO (-8690 4980);
FORCEPROP 1 LASTPIN (-8700 4800) $PN 2
J 0
(-8690 4780);
DISPLAY 0.489362 (-8690 4780);
PAINT MONO (-8690 4780);
FORCEPROP 1 LAST MATERIAL X6S
J 0
(-8650 4800);
DISPLAY 0.489362 (-8650 4800);
PAINT SKYBLUE (-8650 4800);
FORCEPROP 1 LAST TOLERANCE 10%
J 0
(-8650 4850);
DISPLAY 0.489362 (-8650 4850);
PAINT SKYBLUE (-8650 4850);
FORCEPROP 1 LAST VALUE 2.2UF
J 0
(-8650 4950);
DISPLAY 0.489362 (-8650 4950);
PAINT SKYBLUE (-8650 4950);
FORCEPROP 1 LAST PART_NUMBER CH5222KEB01
J 0
(-8650 4750);
DISPLAY 0.489362 (-8650 4750);
PAINT SKYBLUE (-8650 4750);
FORCEPROP 1 LAST VOLTAGE 10V
J 0
(-8650 4900);
DISPLAY 0.489362 (-8650 4900);
PAINT SKYBLUE (-8650 4900);
FORCEPROP 1 LAST PACK_TYPE C0402
J 0
(-8650 4700);
DISPLAY 0.489362 (-8650 4700);
PAINT SKYBLUE (-8650 4700);
FORCEPROP 2 LAST CDS_LIB pure_quanta
J 0
(-8700 4900);
DISPLAY INVISIBLE (-8700 4900);
FORCEPROP 1 LAST PATH I156
J 0
(-8650 5050);
DISPLAY 0.978723 (-8650 5050);
PAINT WHITE (-8650 5050);
DISPLAY INVISIBLE (-8650 5050);
FORCEADD UNIVERSAL_GND..1
(-8700 4700);
FORCEPROP 3 LASTPIN (-8700 4750) SIG_NAME GND\g
J 0
(-8690 4760);
DISPLAY 0.659574 (-8690 4760);
PAINT MONO (-8690 4760);
DISPLAY INVISIBLE (-8690 4760);
FORCEPROP 2 LAST CDS_LIB pure_quanta_power
J 0
(-8700 4700);
DISPLAY INVISIBLE (-8700 4700);
FORCEPROP 1 LAST PATH I157
J 0
(-8625 4700);
DISPLAY 0.872340 (-8625 4700);
PAINT AQUA (-8625 4700);
DISPLAY INVISIBLE (-8625 4700);
FORCEPROP 1 LAST HDL_POWER GND
J 1
(-8675 4625);
DISPLAY 0.872340 (-8675 4625);
PAINT GREEN (-8675 4625);
DISPLAY INVISIBLE (-8675 4625);
FORCEADD UNIVERSAL_GND..1
(-8350 5150);
FORCEPROP 3 LASTPIN (-8350 5200) SIG_NAME GND\g
J 0
(-8340 5210);
DISPLAY 0.659574 (-8340 5210);
PAINT MONO (-8340 5210);
DISPLAY INVISIBLE (-8340 5210);
FORCEPROP 2 LAST CDS_LIB pure_quanta_power
J 0
(-8350 5150);
DISPLAY INVISIBLE (-8350 5150);
FORCEPROP 1 LAST PATH I158
J 0
(-8275 5150);
DISPLAY 0.872340 (-8275 5150);
PAINT AQUA (-8275 5150);
DISPLAY INVISIBLE (-8275 5150);
FORCEPROP 1 LAST HDL_POWER GND
J 1
(-8325 5075);
DISPLAY 0.872340 (-8325 5075);
PAINT GREEN (-8325 5075);
DISPLAY INVISIBLE (-8325 5075);
FORCEADD Q_RES..2
(-8700 5375);
FORCEPROP 1 LAST LOCATION PR79
J 0
(-8655 5500);
DISPLAY 0.489362 (-8655 5500);
PAINT SKYBLUE (-8655 5500);
FORCEPROP 0 LAST $SEC 1
J 0
(-8650 5550);
DISPLAY 0.680851 (-8650 5550);
PAINT MONO (-8650 5550);
DISPLAY INVISIBLE (-8650 5550);
FORCEPROP 0 LAST CDS_SEC 1
J 0
(-8650 5550);
DISPLAY 1.021277 (-8650 5550);
DISPLAY INVISIBLE (-8650 5550);
FORCEPROP 1 LASTPIN (-8700 5475) $PN 1
J 0
(-8695 5437);
DISPLAY 0.489362 (-8695 5437);
PAINT MONO (-8695 5437);
FORCEPROP 1 LASTPIN (-8700 5275) $PN 2
J 0
(-8695 5285);
DISPLAY 0.489362 (-8695 5285);
PAINT MONO (-8695 5285);
FORCEPROP 1 LAST WATTAGE 1/16W
J 0
(-8650 5350);
DISPLAY 0.489362 (-8650 5350);
PAINT SKYBLUE (-8650 5350);
FORCEPROP 1 LAST MATERIAL CHIP
J 0
(-8650 5300);
DISPLAY 0.489362 (-8650 5300);
PAINT SKYBLUE (-8650 5300);
FORCEPROP 1 LAST TOLERANCE 1%
J 0
(-8650 5400);
DISPLAY 0.489362 (-8650 5400);
PAINT SKYBLUE (-8650 5400);
FORCEPROP 1 LAST VALUE 2.2
J 0
(-8650 5450);
DISPLAY 0.489362 (-8650 5450);
PAINT SKYBLUE (-8650 5450);
FORCEPROP 1 LAST PART_NUMBER CS-2202FB00
J 0
(-8650 5250);
DISPLAY 0.489362 (-8650 5250);
PAINT SKYBLUE (-8650 5250);
FORCEPROP 1 LAST PACK_TYPE 0402LF
J 0
(-8650 5200);
DISPLAY 0.489362 (-8650 5200);
PAINT SKYBLUE (-8650 5200);
FORCEPROP 2 LAST CDS_LIB pure_quanta
J 0
(-8700 5375);
DISPLAY INVISIBLE (-8700 5375);
FORCEPROP 1 LAST PATH I159
J 0
(-8650 5550);
DISPLAY 0.978723 (-8650 5550);
PAINT WHITE (-8650 5550);
DISPLAY INVISIBLE (-8650 5550);
FORCEADD OFFPAGE..5
(-8275 3950);
FORCEPROP 2 LAST $XR3 176 
J 0
(-8650 3914);
DISPLAY 0.638298 (-8650 3914);
PAINT MONO (-8650 3914);
FORCEPROP 2 LAST $XR2 179 
J 0
(-8530 3914);
DISPLAY 0.638298 (-8530 3914);
PAINT MONO (-8530 3914);
FORCEPROP 2 LAST $XR1 178 
J 0
(-8650 3950);
DISPLAY 0.638298 (-8650 3950);
PAINT MONO (-8650 3950);
FORCEPROP 2 LAST $XR0 177 
J 0
(-8530 3950);
DISPLAY 0.638298 (-8530 3950);
PAINT MONO (-8530 3950);
FORCEPROP 2 LAST PATH I16
J 0
(-8550 4025);
DISPLAY 1.021277 (-8550 4025);
DISPLAY INVISIBLE (-8550 4025);
FORCEPROP 2 LAST CDS_LIB standard
J 0
(-8275 3950);
DISPLAY INVISIBLE (-8275 3950);
FORCEPROP 1 LAST COMMENT_BODY TRUE
J 0
(-8175 3875);
DISPLAY 0.872340 (-8175 3875);
PAINT GREEN (-8175 3875);
DISPLAY INVISIBLE (-8175 3875);
FORCEPROP 1 LAST OFFPAGE TRUE
J 0
(-7950 3825);
DISPLAY 0.872340 (-7950 3825);
PAINT GREEN (-7950 3825);
DISPLAY INVISIBLE (-7950 3825);
FORCEADD Q_CAP..1
(-8350 5400);
FORCEPROP 1 LAST LOCATION PC81_C1P0_1
J 0
(-8300 5500);
DISPLAY 0.489362 (-8300 5500);
PAINT SKYBLUE (-8300 5500);
FORCEPROP 0 LAST $SEC 1
J 0
(-8300 5550);
DISPLAY 0.680851 (-8300 5550);
PAINT MONO (-8300 5550);
DISPLAY INVISIBLE (-8300 5550);
FORCEPROP 0 LAST CDS_SEC 1
J 0
(-8300 5550);
DISPLAY 1.021277 (-8300 5550);
DISPLAY INVISIBLE (-8300 5550);
FORCEPROP 1 LASTPIN (-8350 5500) $PN 1
J 0
(-8340 5480);
DISPLAY 0.489362 (-8340 5480);
PAINT MONO (-8340 5480);
FORCEPROP 1 LASTPIN (-8350 5300) $PN 2
J 0
(-8340 5280);
DISPLAY 0.489362 (-8340 5280);
PAINT MONO (-8340 5280);
FORCEPROP 1 LAST MATERIAL X6S
J 0
(-8300 5300);
DISPLAY 0.489362 (-8300 5300);
PAINT SKYBLUE (-8300 5300);
FORCEPROP 1 LAST TOLERANCE 10%
J 0
(-8300 5350);
DISPLAY 0.489362 (-8300 5350);
PAINT SKYBLUE (-8300 5350);
FORCEPROP 1 LAST VALUE 2.2UF
J 0
(-8300 5450);
DISPLAY 0.489362 (-8300 5450);
PAINT SKYBLUE (-8300 5450);
FORCEPROP 1 LAST PART_NUMBER CH5222KEB01
J 0
(-8300 5250);
DISPLAY 0.489362 (-8300 5250);
PAINT SKYBLUE (-8300 5250);
FORCEPROP 1 LAST VOLTAGE 10V
J 0
(-8300 5400);
DISPLAY 0.489362 (-8300 5400);
PAINT SKYBLUE (-8300 5400);
FORCEPROP 1 LAST PACK_TYPE C0402
J 0
(-8300 5200);
DISPLAY 0.489362 (-8300 5200);
PAINT SKYBLUE (-8300 5200);
FORCEPROP 2 LAST CDS_LIB pure_quanta
J 0
(-8350 5400);
DISPLAY INVISIBLE (-8350 5400);
FORCEPROP 1 LAST PATH I160
J 0
(-8300 5550);
DISPLAY 0.978723 (-8300 5550);
PAINT WHITE (-8300 5550);
DISPLAY INVISIBLE (-8300 5550);
FORCEADD Q_CAP..1
(-8600 1925);
FORCEPROP 1 LAST LOCATION PC80
J 0
(-8550 2025);
DISPLAY 0.489362 (-8550 2025);
PAINT SKYBLUE (-8550 2025);
FORCEPROP 0 LAST $SEC 1
J 0
(-8550 2075);
DISPLAY 0.680851 (-8550 2075);
PAINT MONO (-8550 2075);
DISPLAY INVISIBLE (-8550 2075);
FORCEPROP 0 LAST CDS_SEC 1
J 0
(-8550 2075);
DISPLAY 1.021277 (-8550 2075);
DISPLAY INVISIBLE (-8550 2075);
FORCEPROP 1 LASTPIN (-8600 2025) $PN 1
J 0
(-8590 2005);
DISPLAY 0.489362 (-8590 2005);
PAINT MONO (-8590 2005);
FORCEPROP 1 LASTPIN (-8600 1825) $PN 2
J 0
(-8590 1805);
DISPLAY 0.489362 (-8590 1805);
PAINT MONO (-8590 1805);
FORCEPROP 1 LAST MATERIAL X6S
J 0
(-8550 1825);
DISPLAY 0.489362 (-8550 1825);
PAINT SKYBLUE (-8550 1825);
FORCEPROP 1 LAST TOLERANCE 10%
J 0
(-8550 1875);
DISPLAY 0.489362 (-8550 1875);
PAINT SKYBLUE (-8550 1875);
FORCEPROP 1 LAST VALUE 2.2UF
J 0
(-8550 1975);
DISPLAY 0.489362 (-8550 1975);
PAINT SKYBLUE (-8550 1975);
FORCEPROP 1 LAST PART_NUMBER CH5222KEB01
J 0
(-8550 1775);
DISPLAY 0.489362 (-8550 1775);
PAINT SKYBLUE (-8550 1775);
FORCEPROP 1 LAST VOLTAGE 10V
J 0
(-8550 1925);
DISPLAY 0.489362 (-8550 1925);
PAINT SKYBLUE (-8550 1925);
FORCEPROP 1 LAST PACK_TYPE C0402
J 0
(-8550 1725);
DISPLAY 0.489362 (-8550 1725);
PAINT SKYBLUE (-8550 1725);
FORCEPROP 2 LAST CDS_LIB pure_quanta
J 0
(-8600 1925);
DISPLAY INVISIBLE (-8600 1925);
FORCEPROP 1 LAST PATH I162
J 0
(-8550 2075);
DISPLAY 0.978723 (-8550 2075);
PAINT WHITE (-8550 2075);
DISPLAY INVISIBLE (-8550 2075);
FORCEADD UNIVERSAL_GND..1
(-8600 1725);
FORCEPROP 3 LASTPIN (-8600 1775) SIG_NAME GND\g
J 0
(-8590 1785);
DISPLAY 0.659574 (-8590 1785);
PAINT MONO (-8590 1785);
DISPLAY INVISIBLE (-8590 1785);
FORCEPROP 2 LAST CDS_LIB pure_quanta_power
J 0
(-8600 1725);
DISPLAY INVISIBLE (-8600 1725);
FORCEPROP 1 LAST PATH I163
J 0
(-8525 1725);
DISPLAY 0.872340 (-8525 1725);
PAINT AQUA (-8525 1725);
DISPLAY INVISIBLE (-8525 1725);
FORCEPROP 1 LAST HDL_POWER GND
J 1
(-8575 1650);
DISPLAY 0.872340 (-8575 1650);
PAINT GREEN (-8575 1650);
DISPLAY INVISIBLE (-8575 1650);
FORCEADD UNIVERSAL_GND..1
(-8250 2225);
FORCEPROP 3 LASTPIN (-8250 2275) SIG_NAME GND\g
J 0
(-8240 2285);
DISPLAY 0.659574 (-8240 2285);
PAINT MONO (-8240 2285);
DISPLAY INVISIBLE (-8240 2285);
FORCEPROP 2 LAST CDS_LIB pure_quanta_power
J 0
(-8250 2225);
DISPLAY INVISIBLE (-8250 2225);
FORCEPROP 1 LAST PATH I164
J 0
(-8175 2225);
DISPLAY 0.872340 (-8175 2225);
PAINT AQUA (-8175 2225);
DISPLAY INVISIBLE (-8175 2225);
FORCEPROP 1 LAST HDL_POWER GND
J 1
(-8225 2150);
DISPLAY 0.872340 (-8225 2150);
PAINT GREEN (-8225 2150);
DISPLAY INVISIBLE (-8225 2150);
FORCEADD Q_RES..2
(-8600 2475);
FORCEPROP 1 LAST LOCATION PR80
J 0
(-8555 2600);
DISPLAY 0.489362 (-8555 2600);
PAINT SKYBLUE (-8555 2600);
FORCEPROP 0 LAST $SEC 1
J 0
(-8550 2650);
DISPLAY 0.680851 (-8550 2650);
PAINT MONO (-8550 2650);
DISPLAY INVISIBLE (-8550 2650);
FORCEPROP 0 LAST CDS_SEC 1
J 0
(-8550 2650);
DISPLAY 1.021277 (-8550 2650);
DISPLAY INVISIBLE (-8550 2650);
FORCEPROP 1 LASTPIN (-8600 2575) $PN 1
J 0
(-8595 2537);
DISPLAY 0.489362 (-8595 2537);
PAINT MONO (-8595 2537);
FORCEPROP 1 LASTPIN (-8600 2375) $PN 2
J 0
(-8595 2385);
DISPLAY 0.489362 (-8595 2385);
PAINT MONO (-8595 2385);
FORCEPROP 1 LAST WATTAGE 1/16W
J 0
(-8550 2450);
DISPLAY 0.489362 (-8550 2450);
PAINT SKYBLUE (-8550 2450);
FORCEPROP 1 LAST MATERIAL CHIP
J 0
(-8550 2400);
DISPLAY 0.489362 (-8550 2400);
PAINT SKYBLUE (-8550 2400);
FORCEPROP 1 LAST TOLERANCE 1%
J 0
(-8550 2500);
DISPLAY 0.489362 (-8550 2500);
PAINT SKYBLUE (-8550 2500);
FORCEPROP 1 LAST VALUE 2.2
J 0
(-8550 2550);
DISPLAY 0.489362 (-8550 2550);
PAINT SKYBLUE (-8550 2550);
FORCEPROP 1 LAST PART_NUMBER CS-2202FB00
J 0
(-8550 2350);
DISPLAY 0.489362 (-8550 2350);
PAINT SKYBLUE (-8550 2350);
FORCEPROP 1 LAST PACK_TYPE 0402LF
J 0
(-8550 2300);
DISPLAY 0.489362 (-8550 2300);
PAINT SKYBLUE (-8550 2300);
FORCEPROP 2 LAST CDS_LIB pure_quanta
J 0
(-8600 2475);
DISPLAY INVISIBLE (-8600 2475);
FORCEPROP 1 LAST PATH I165
J 0
(-8550 2650);
DISPLAY 0.978723 (-8550 2650);
PAINT WHITE (-8550 2650);
DISPLAY INVISIBLE (-8550 2650);
FORCEADD Q_CAP..1
(-8250 2500);
FORCEPROP 1 LAST LOCATION PC82_C1P0_2
J 0
(-8200 2600);
DISPLAY 0.489362 (-8200 2600);
PAINT SKYBLUE (-8200 2600);
FORCEPROP 0 LAST $SEC 1
J 0
(-8200 2650);
DISPLAY 0.680851 (-8200 2650);
PAINT MONO (-8200 2650);
DISPLAY INVISIBLE (-8200 2650);
FORCEPROP 0 LAST CDS_SEC 1
J 0
(-8200 2650);
DISPLAY 1.021277 (-8200 2650);
DISPLAY INVISIBLE (-8200 2650);
FORCEPROP 1 LASTPIN (-8250 2600) $PN 1
J 0
(-8240 2580);
DISPLAY 0.489362 (-8240 2580);
PAINT MONO (-8240 2580);
FORCEPROP 1 LASTPIN (-8250 2400) $PN 2
J 0
(-8240 2380);
DISPLAY 0.489362 (-8240 2380);
PAINT MONO (-8240 2380);
FORCEPROP 1 LAST MATERIAL X6S
J 0
(-8200 2400);
DISPLAY 0.489362 (-8200 2400);
PAINT SKYBLUE (-8200 2400);
FORCEPROP 1 LAST TOLERANCE 10%
J 0
(-8200 2450);
DISPLAY 0.489362 (-8200 2450);
PAINT SKYBLUE (-8200 2450);
FORCEPROP 1 LAST VALUE 2.2UF
J 0
(-8200 2550);
DISPLAY 0.489362 (-8200 2550);
PAINT SKYBLUE (-8200 2550);
FORCEPROP 1 LAST PART_NUMBER CH5222KEB01
J 0
(-8200 2350);
DISPLAY 0.489362 (-8200 2350);
PAINT SKYBLUE (-8200 2350);
FORCEPROP 1 LAST VOLTAGE 10V
J 0
(-8200 2500);
DISPLAY 0.489362 (-8200 2500);
PAINT SKYBLUE (-8200 2500);
FORCEPROP 1 LAST PACK_TYPE C0402
J 0
(-8200 2300);
DISPLAY 0.489362 (-8200 2300);
PAINT SKYBLUE (-8200 2300);
FORCEPROP 2 LAST CDS_LIB pure_quanta
J 0
(-8250 2500);
DISPLAY INVISIBLE (-8250 2500);
FORCEPROP 1 LAST PATH I166
J 0
(-8200 2650);
DISPLAY 0.978723 (-8200 2650);
PAINT WHITE (-8200 2650);
DISPLAY INVISIBLE (-8200 2650);
FORCEADD Q_CAPP..1
(-3425 3000);
FORCEPROP 1 LAST LOCATION PC102
J 0
(-3375 3100);
DISPLAY 0.489362 (-3375 3100);
PAINT SKYBLUE (-3375 3100);
FORCEPROP 0 LAST $SEC 1
J 0
(-3375 3150);
DISPLAY 0.680851 (-3375 3150);
PAINT MONO (-3375 3150);
DISPLAY INVISIBLE (-3375 3150);
FORCEPROP 0 LAST CDS_SEC 1
J 0
(-3375 3150);
DISPLAY 1.021277 (-3375 3150);
DISPLAY INVISIBLE (-3375 3150);
FORCEPROP 1 LASTPIN (-3425 3100) $PN 1
J 0
(-3415 3085);
DISPLAY 0.489362 (-3415 3085);
PAINT MONO (-3415 3085);
FORCEPROP 1 LASTPIN (-3425 2900) $PN 2
J 0
(-3415 2885);
DISPLAY 0.489362 (-3415 2885);
PAINT MONO (-3415 2885);
FORCEPROP 1 LAST PACK_TYPE SMLF
J 0
(-3375 2850);
DISPLAY 0.489362 (-3375 2850);
PAINT SKYBLUE (-3375 2850);
FORCEPROP 1 LAST VOLTAGE 4V
J 0
(-3375 2950);
DISPLAY 0.489362 (-3375 2950);
PAINT SKYBLUE (-3375 2950);
FORCEPROP 1 LAST TOLERANCE 20%
J 0
(-3375 3000);
DISPLAY 0.489362 (-3375 3000);
PAINT SKYBLUE (-3375 3000);
FORCEPROP 1 LAST VALUE 220UF
J 0
(-3375 3050);
DISPLAY 0.489362 (-3375 3050);
PAINT SKYBLUE (-3375 3050);
FORCEPROP 1 LAST MATERIAL SPCAP
J 0
(-3375 2900);
DISPLAY 0.489362 (-3375 2900);
PAINT SKYBLUE (-3375 2900);
FORCEPROP 1 LAST PART_NUMBER CH122KM8801
J 0
(-3375 2800);
DISPLAY 0.489362 (-3375 2800);
PAINT SKYBLUE (-3375 2800);
FORCEPROP 1 LAST PATH I168
J 0
(-3375 3150);
DISPLAY 0.978723 (-3375 3150);
DISPLAY INVISIBLE (-3375 3150);
FORCEPROP 2 LAST CDS_LIB pure_quanta
J 0
(-3425 3000);
DISPLAY INVISIBLE (-3425 3000);
FORCEADD OFFPAGE..6
R 2
(-3000 1250);
FORCEPROP 2 LAST $XR0 178 
J 0
(-2756 1250);
DISPLAY 0.638298 (-2756 1250);
PAINT MONO (-2756 1250);
FORCEPROP 1 LAST OFFPAGE TRUE
J 2
(-3325 1125);
DISPLAY 0.872340 (-3325 1125);
PAINT GREEN (-3325 1125);
DISPLAY INVISIBLE (-3325 1125);
FORCEPROP 1 LAST COMMENT_BODY TRUE
J 2
(-3100 1175);
DISPLAY 0.872340 (-3100 1175);
PAINT GREEN (-3100 1175);
DISPLAY INVISIBLE (-3100 1175);
FORCEPROP 2 LAST CDS_LIB standard
J 0
(-3000 1250);
DISPLAY INVISIBLE (-3000 1250);
FORCEPROP 2 LAST PATH I169
J 0
(-2800 1325);
DISPLAY 1.021277 (-2800 1325);
DISPLAY INVISIBLE (-2800 1325);
FORCEADD Q_CAP..1
(-5600 4275);
FORCEPROP 1 LAST LOCATION PC189
J 0
(-5550 4375);
DISPLAY 0.489362 (-5550 4375);
PAINT SKYBLUE (-5550 4375);
FORCEPROP 0 LAST $SEC 1
J 0
(-5550 4425);
DISPLAY 0.680851 (-5550 4425);
PAINT MONO (-5550 4425);
DISPLAY INVISIBLE (-5550 4425);
FORCEPROP 0 LAST CDS_SEC 1
J 0
(-5550 4425);
DISPLAY 1.021277 (-5550 4425);
DISPLAY INVISIBLE (-5550 4425);
FORCEPROP 1 LASTPIN (-5600 4375) $PN 1
J 0
(-5590 4355);
DISPLAY 0.489362 (-5590 4355);
PAINT MONO (-5590 4355);
FORCEPROP 1 LASTPIN (-5600 4175) $PN 2
J 0
(-5590 4155);
DISPLAY 0.489362 (-5590 4155);
PAINT MONO (-5590 4155);
FORCEPROP 1 LAST MATERIAL EMPTY
J 0
(-5550 4175);
DISPLAY 0.489362 (-5550 4175);
PAINT RED (-5550 4175);
FORCEPROP 1 LAST TOLERANCE 10%
J 0
(-5550 4225);
DISPLAY 0.489362 (-5550 4225);
PAINT SKYBLUE (-5550 4225);
FORCEPROP 1 LAST VALUE 560PF
J 0
(-5550 4325);
DISPLAY 0.489362 (-5550 4325);
PAINT SKYBLUE (-5550 4325);
FORCEPROP 1 LAST PART_NUMBER CH1566K1B09
J 0
(-5550 4125);
DISPLAY 0.489362 (-5550 4125);
PAINT SKYBLUE (-5550 4125);
FORCEPROP 1 LAST VOLTAGE 50V
J 0
(-5550 4275);
DISPLAY 0.489362 (-5550 4275);
PAINT SKYBLUE (-5550 4275);
FORCEPROP 1 LAST PACK_TYPE C0402
J 0
(-5550 4075);
DISPLAY 0.489362 (-5550 4075);
PAINT SKYBLUE (-5550 4075);
FORCEPROP 2 LAST CDS_LIB pure_quanta
J 0
(-5600 4275);
DISPLAY INVISIBLE (-5600 4275);
FORCEPROP 1 LAST PATH I170
J 0
(-5550 4425);
DISPLAY 0.978723 (-5550 4425);
PAINT WHITE (-5550 4425);
DISPLAY INVISIBLE (-5550 4425);
FORCEADD Q_RES..2
(-5600 3825);
FORCEPROP 1 LAST LOCATION PR506
J 0
(-5555 3950);
DISPLAY 0.489362 (-5555 3950);
PAINT SKYBLUE (-5555 3950);
FORCEPROP 0 LAST $SEC 1
J 0
(-5550 4000);
DISPLAY 0.680851 (-5550 4000);
PAINT MONO (-5550 4000);
DISPLAY INVISIBLE (-5550 4000);
FORCEPROP 0 LAST CDS_SEC 1
J 0
(-5550 4000);
DISPLAY 1.021277 (-5550 4000);
DISPLAY INVISIBLE (-5550 4000);
FORCEPROP 1 LASTPIN (-5600 3925) $PN 1
J 0
(-5595 3887);
DISPLAY 0.489362 (-5595 3887);
PAINT MONO (-5595 3887);
FORCEPROP 1 LASTPIN (-5600 3725) $PN 2
J 0
(-5595 3735);
DISPLAY 0.489362 (-5595 3735);
PAINT MONO (-5595 3735);
FORCEPROP 1 LAST PART_NUMBER CS-1504FB00
J 0
(-5560 3700);
DISPLAY 0.489362 (-5560 3700);
PAINT SKYBLUE (-5560 3700);
FORCEPROP 1 LAST MATERIAL EMPTY
J 0
(-5560 3750);
DISPLAY 0.489362 (-5560 3750);
PAINT RED (-5560 3750);
FORCEPROP 1 LAST WATTAGE 1/8W
J 0
(-5560 3800);
DISPLAY 0.489362 (-5560 3800);
PAINT SKYBLUE (-5560 3800);
FORCEPROP 1 LAST TOLERANCE 1%
J 0
(-5555 3850);
DISPLAY 0.489362 (-5555 3850);
PAINT SKYBLUE (-5555 3850);
FORCEPROP 1 LAST PACK_TYPE 0402LF
J 0
(-5560 3650);
DISPLAY 0.489362 (-5560 3650);
PAINT SKYBLUE (-5560 3650);
FORCEPROP 1 LAST VALUE 1.5
J 0
(-5555 3900);
DISPLAY 0.489362 (-5555 3900);
PAINT SKYBLUE (-5555 3900);
FORCEPROP 2 LAST CDS_LIB pure_quanta
J 0
(-5600 3825);
DISPLAY INVISIBLE (-5600 3825);
FORCEPROP 1 LAST PATH I171
J 0
(-5550 4000);
DISPLAY 0.978723 (-5550 4000);
PAINT WHITE (-5550 4000);
DISPLAY INVISIBLE (-5550 4000);
FORCEADD UNIVERSAL_GND..1
(-5600 3600);
FORCEPROP 3 LASTPIN (-5600 3650) SIG_NAME GND\g
J 0
(-5590 3660);
DISPLAY 0.659574 (-5590 3660);
PAINT MONO (-5590 3660);
DISPLAY INVISIBLE (-5590 3660);
FORCEPROP 2 LAST CDS_LIB pure_quanta_power
J 0
(-5600 3600);
DISPLAY INVISIBLE (-5600 3600);
FORCEPROP 1 LAST PATH I172
J 0
(-5525 3600);
DISPLAY 0.872340 (-5525 3600);
PAINT AQUA (-5525 3600);
DISPLAY INVISIBLE (-5525 3600);
FORCEPROP 1 LAST HDL_POWER GND
J 1
(-5575 3525);
DISPLAY 0.872340 (-5575 3525);
PAINT GREEN (-5575 3525);
DISPLAY INVISIBLE (-5575 3525);
FORCEADD Q_CAP..1
(-5600 1325);
FORCEPROP 1 LAST LOCATION PC190
J 0
(-5550 1425);
DISPLAY 0.489362 (-5550 1425);
PAINT SKYBLUE (-5550 1425);
FORCEPROP 0 LAST $SEC 1
J 0
(-5550 1475);
DISPLAY 0.680851 (-5550 1475);
PAINT MONO (-5550 1475);
DISPLAY INVISIBLE (-5550 1475);
FORCEPROP 0 LAST CDS_SEC 1
J 0
(-5550 1475);
DISPLAY 1.021277 (-5550 1475);
DISPLAY INVISIBLE (-5550 1475);
FORCEPROP 1 LASTPIN (-5600 1425) $PN 1
J 0
(-5590 1405);
DISPLAY 0.489362 (-5590 1405);
PAINT MONO (-5590 1405);
FORCEPROP 1 LASTPIN (-5600 1225) $PN 2
J 0
(-5590 1205);
DISPLAY 0.489362 (-5590 1205);
PAINT MONO (-5590 1205);
FORCEPROP 1 LAST MATERIAL EMPTY
J 0
(-5550 1225);
DISPLAY 0.489362 (-5550 1225);
PAINT RED (-5550 1225);
FORCEPROP 1 LAST TOLERANCE 10%
J 0
(-5550 1275);
DISPLAY 0.489362 (-5550 1275);
PAINT SKYBLUE (-5550 1275);
FORCEPROP 1 LAST VALUE 560PF
J 0
(-5550 1375);
DISPLAY 0.489362 (-5550 1375);
PAINT SKYBLUE (-5550 1375);
FORCEPROP 1 LAST PART_NUMBER CH1566K1B09
J 0
(-5550 1175);
DISPLAY 0.489362 (-5550 1175);
PAINT SKYBLUE (-5550 1175);
FORCEPROP 1 LAST VOLTAGE 50V
J 0
(-5550 1325);
DISPLAY 0.489362 (-5550 1325);
PAINT SKYBLUE (-5550 1325);
FORCEPROP 1 LAST PACK_TYPE C0402
J 0
(-5550 1125);
DISPLAY 0.489362 (-5550 1125);
PAINT SKYBLUE (-5550 1125);
FORCEPROP 2 LAST CDS_LIB pure_quanta
J 0
(-5600 1325);
DISPLAY INVISIBLE (-5600 1325);
FORCEPROP 1 LAST PATH I173
J 0
(-5550 1475);
DISPLAY 0.978723 (-5550 1475);
PAINT WHITE (-5550 1475);
DISPLAY INVISIBLE (-5550 1475);
FORCEADD Q_RES..2
(-5600 875);
FORCEPROP 1 LAST LOCATION PR507
J 0
(-5555 1000);
DISPLAY 0.489362 (-5555 1000);
PAINT SKYBLUE (-5555 1000);
FORCEPROP 0 LAST $SEC 1
J 0
(-5550 1050);
DISPLAY 0.680851 (-5550 1050);
PAINT MONO (-5550 1050);
DISPLAY INVISIBLE (-5550 1050);
FORCEPROP 0 LAST CDS_SEC 1
J 0
(-5550 1050);
DISPLAY 1.021277 (-5550 1050);
DISPLAY INVISIBLE (-5550 1050);
FORCEPROP 1 LASTPIN (-5600 975) $PN 1
J 0
(-5595 937);
DISPLAY 0.489362 (-5595 937);
PAINT MONO (-5595 937);
FORCEPROP 1 LASTPIN (-5600 775) $PN 2
J 0
(-5595 785);
DISPLAY 0.489362 (-5595 785);
PAINT MONO (-5595 785);
FORCEPROP 1 LAST WATTAGE 1/8W
J 0
(-5560 850);
DISPLAY 0.489362 (-5560 850);
PAINT SKYBLUE (-5560 850);
FORCEPROP 1 LAST MATERIAL EMPTY
J 0
(-5560 800);
DISPLAY 0.489362 (-5560 800);
PAINT RED (-5560 800);
FORCEPROP 1 LAST TOLERANCE 1%
J 0
(-5555 900);
DISPLAY 0.489362 (-5555 900);
PAINT SKYBLUE (-5555 900);
FORCEPROP 1 LAST VALUE 1.5
J 0
(-5555 950);
DISPLAY 0.489362 (-5555 950);
PAINT SKYBLUE (-5555 950);
FORCEPROP 1 LAST PART_NUMBER CS-1504FB00
J 0
(-5560 750);
DISPLAY 0.489362 (-5560 750);
PAINT SKYBLUE (-5560 750);
FORCEPROP 1 LAST PACK_TYPE 0402LF
J 0
(-5560 700);
DISPLAY 0.489362 (-5560 700);
PAINT SKYBLUE (-5560 700);
FORCEPROP 2 LAST CDS_LIB pure_quanta
J 0
(-5600 875);
DISPLAY INVISIBLE (-5600 875);
FORCEPROP 1 LAST PATH I174
J 0
(-5550 1050);
DISPLAY 0.978723 (-5550 1050);
PAINT WHITE (-5550 1050);
DISPLAY INVISIBLE (-5550 1050);
FORCEADD UNIVERSAL_GND..1
(-5600 650);
FORCEPROP 3 LASTPIN (-5600 700) SIG_NAME GND\g
J 0
(-5590 710);
DISPLAY 0.659574 (-5590 710);
PAINT MONO (-5590 710);
DISPLAY INVISIBLE (-5590 710);
FORCEPROP 2 LAST CDS_LIB pure_quanta_power
J 0
(-5600 650);
DISPLAY INVISIBLE (-5600 650);
FORCEPROP 1 LAST PATH I175
J 0
(-5525 650);
DISPLAY 0.872340 (-5525 650);
PAINT AQUA (-5525 650);
DISPLAY INVISIBLE (-5525 650);
FORCEPROP 1 LAST HDL_POWER GND
J 1
(-5575 575);
DISPLAY 0.872340 (-5575 575);
PAINT GREEN (-5575 575);
DISPLAY INVISIBLE (-5575 575);
FORCEADD OFFPAGE..3
R 2
(-5100 4200);
FORCEPROP 2 LAST $XR0 179 
J 0
(-5380 4200);
DISPLAY 0.638298 (-5380 4200);
PAINT MONO (-5380 4200);
FORCEPROP 1 LAST OFFPAGE TRUE
J 2
(-5425 4075);
DISPLAY 0.872340 (-5425 4075);
PAINT GREEN (-5425 4075);
DISPLAY INVISIBLE (-5425 4075);
FORCEPROP 2 LAST PATH I176
J 2
(-5300 4275);
DISPLAY 1.021277 (-5300 4275);
DISPLAY INVISIBLE (-5300 4275);
FORCEPROP 2 LAST CDS_LIB standard
J 2
(-5100 4200);
DISPLAY INVISIBLE (-5100 4200);
FORCEPROP 1 LAST COMMENT_BODY TRUE
J 2
(-5050 4100);
DISPLAY 0.872340 (-5050 4100);
PAINT GREEN (-5050 4100);
DISPLAY INVISIBLE (-5050 4100);
FORCEADD VCC_CORE..1
(-8600 2900);
FORCEPROP 3 LASTPIN (-8600 2850) SIG_NAME PVDDCR_CPU1_P0_PVCC\g
J 0
(-8590 2860);
DISPLAY 0.659574 (-8590 2860);
PAINT MONO (-8590 2860);
DISPLAY INVISIBLE (-8590 2860);
FORCEPROP 1 LAST HDL_POWER PVDDCR_CPU1_P0_PVCC
J 1
(-8600 2950);
DISPLAY 0.489362 (-8600 2950);
PAINT GREEN (-8600 2950);
FORCEPROP 2 LAST CDS_LIB pure_quanta_power
J 0
(-8600 2900);
DISPLAY INVISIBLE (-8600 2900);
FORCEPROP 1 LAST PATH I182
J 0
(-8550 2925);
DISPLAY 0.872340 (-8550 2925);
PAINT AQUA (-8550 2925);
DISPLAY INVISIBLE (-8550 2925);
FORCEADD VCC_CORE..1
(-8500 5975);
FORCEPROP 3 LASTPIN (-8500 5925) SIG_NAME PVDDCR_CPU1_P0_PVCC\g
J 0
(-8490 5935);
DISPLAY 0.659574 (-8490 5935);
PAINT MONO (-8490 5935);
DISPLAY INVISIBLE (-8490 5935);
FORCEPROP 1 LAST HDL_POWER PVDDCR_CPU1_P0_PVCC
J 1
(-8500 6025);
DISPLAY 0.489362 (-8500 6025);
PAINT GREEN (-8500 6025);
FORCEPROP 2 LAST CDS_LIB pure_quanta_power
J 0
(-8500 5975);
DISPLAY INVISIBLE (-8500 5975);
FORCEPROP 1 LAST PATH I183
J 0
(-8450 6000);
DISPLAY 0.872340 (-8450 6000);
PAINT AQUA (-8450 6000);
DISPLAY INVISIBLE (-8450 6000);
FORCEADD Q_RES..1
R 1
(-9350 5775);
FORCEPROP 1 LAST LOCATION PR442
J 0
(-9325 5925);
DISPLAY 0.489362 (-9325 5925);
PAINT SKYBLUE (-9325 5925);
FORCEPROP 0 LAST $SEC 1
R 1
J 0
(-9325 5950);
DISPLAY 0.680851 (-9325 5950);
PAINT MONO (-9325 5950);
DISPLAY INVISIBLE (-9325 5950);
FORCEPROP 0 LAST CDS_SEC 1
R 1
J 0
(-9325 5950);
DISPLAY 1.021277 (-9325 5950);
DISPLAY INVISIBLE (-9325 5950);
FORCEPROP 1 LASTPIN (-9350 5675) $PN 1
R 1
J 0
(-9362 5687);
DISPLAY 0.787234 (-9362 5687);
PAINT MONO (-9362 5687);
DISPLAY INVISIBLE (-9362 5687);
FORCEPROP 1 LASTPIN (-9350 5875) $PN 2
R 1
J 0
(-9362 5837);
DISPLAY 0.787234 (-9362 5837);
PAINT MONO (-9362 5837);
DISPLAY INVISIBLE (-9362 5837);
FORCEPROP 1 LAST WATTAGE 1/16W
J 0
(-9325 5775);
DISPLAY 0.489362 (-9325 5775);
PAINT SKYBLUE (-9325 5775);
FORCEPROP 1 LAST MATERIAL CHIP
J 0
(-9325 5725);
DISPLAY 0.489362 (-9325 5725);
PAINT SKYBLUE (-9325 5725);
FORCEPROP 1 LAST TOLERANCE 5%
J 0
(-9325 5825);
DISPLAY 0.489362 (-9325 5825);
PAINT SKYBLUE (-9325 5825);
FORCEPROP 1 LAST VALUE 0
J 2
(-9300 5875);
DISPLAY 0.489362 (-9300 5875);
PAINT SKYBLUE (-9300 5875);
FORCEPROP 1 LAST PART_NUMBER CS00002JB38
J 0
(-9325 5675);
DISPLAY 0.489362 (-9325 5675);
PAINT SKYBLUE (-9325 5675);
FORCEPROP 1 LAST PACK_TYPE 0402LF
J 0
(-9325 5625);
DISPLAY 0.489362 (-9325 5625);
PAINT SKYBLUE (-9325 5625);
FORCEPROP 2 LAST CDS_LIB pure_quanta
J 0
(-9350 5775);
DISPLAY INVISIBLE (-9350 5775);
FORCEPROP 1 LAST PATH I184
R 1
J 0
(-9500 5725);
DISPLAY 0.978723 (-9500 5725);
PAINT WHITE (-9500 5725);
DISPLAY INVISIBLE (-9500 5725);
FORCEADD VCC_CORE..1
(-9350 5975);
FORCEPROP 3 LASTPIN (-9350 5925) SIG_NAME P5V_STBY\g
J 0
(-9340 5935);
DISPLAY 0.659574 (-9340 5935);
PAINT MONO (-9340 5935);
DISPLAY INVISIBLE (-9340 5935);
FORCEPROP 1 LAST HDL_POWER P5V_STBY
J 1
(-9350 6025);
DISPLAY 0.489362 (-9350 6025);
PAINT GREEN (-9350 6025);
FORCEPROP 2 LAST CDS_LIB pure_quanta_power
J 0
(-9350 5975);
DISPLAY INVISIBLE (-9350 5975);
FORCEPROP 1 LAST PATH I185
J 0
(-9300 6000);
DISPLAY 0.872340 (-9300 6000);
PAINT AQUA (-9300 6000);
DISPLAY INVISIBLE (-9300 6000);
FORCEADD VCC_CORE..1
(-9000 5975);
FORCEPROP 3 LASTPIN (-9000 5925) SIG_NAME P3V3_STBY\g
J 0
(-8990 5935);
DISPLAY 0.659574 (-8990 5935);
PAINT MONO (-8990 5935);
DISPLAY INVISIBLE (-8990 5935);
FORCEPROP 1 LAST HDL_POWER P3V3_STBY
J 1
(-9000 6025);
DISPLAY 0.489362 (-9000 6025);
PAINT GREEN (-9000 6025);
FORCEPROP 2 LAST CDS_LIB pure_quanta_power
J 0
(-9000 5975);
DISPLAY INVISIBLE (-9000 5975);
FORCEPROP 1 LAST PATH I186
J 0
(-8950 6000);
DISPLAY 0.872340 (-8950 6000);
PAINT AQUA (-8950 6000);
DISPLAY INVISIBLE (-8950 6000);
FORCEADD Q_RES..1
R 1
(-9000 5775);
FORCEPROP 1 LAST LOCATION PR443
J 0
(-8950 5925);
DISPLAY 0.489362 (-8950 5925);
PAINT SKYBLUE (-8950 5925);
FORCEPROP 0 LAST $SEC 1
R 1
J 0
(-8950 5950);
DISPLAY 0.680851 (-8950 5950);
PAINT MONO (-8950 5950);
DISPLAY INVISIBLE (-8950 5950);
FORCEPROP 0 LAST CDS_SEC 1
R 1
J 0
(-8950 5950);
DISPLAY 1.021277 (-8950 5950);
DISPLAY INVISIBLE (-8950 5950);
FORCEPROP 1 LASTPIN (-9000 5675) $PN 1
R 1
J 0
(-9012 5687);
DISPLAY 0.787234 (-9012 5687);
PAINT MONO (-9012 5687);
DISPLAY INVISIBLE (-9012 5687);
FORCEPROP 1 LASTPIN (-9000 5875) $PN 2
R 1
J 0
(-9012 5837);
DISPLAY 0.787234 (-9012 5837);
PAINT MONO (-9012 5837);
DISPLAY INVISIBLE (-9012 5837);
FORCEPROP 1 LAST WATTAGE 1/16W
J 0
(-8950 5775);
DISPLAY 0.489362 (-8950 5775);
PAINT SKYBLUE (-8950 5775);
FORCEPROP 1 LAST MATERIAL EMPTY
J 0
(-8950 5725);
DISPLAY 0.489362 (-8950 5725);
PAINT RED (-8950 5725);
FORCEPROP 1 LAST TOLERANCE 5%
J 0
(-8950 5825);
DISPLAY 0.489362 (-8950 5825);
PAINT SKYBLUE (-8950 5825);
FORCEPROP 1 LAST VALUE 0
J 2
(-8925 5875);
DISPLAY 0.489362 (-8925 5875);
PAINT SKYBLUE (-8925 5875);
FORCEPROP 1 LAST PART_NUMBER CS00002JB38
J 0
(-8950 5675);
DISPLAY 0.489362 (-8950 5675);
PAINT SKYBLUE (-8950 5675);
FORCEPROP 1 LAST PACK_TYPE 0402LF
J 0
(-8950 5625);
DISPLAY 0.489362 (-8950 5625);
PAINT SKYBLUE (-8950 5625);
FORCEPROP 2 LAST CDS_LIB pure_quanta
J 0
(-9000 5775);
DISPLAY INVISIBLE (-9000 5775);
FORCEPROP 1 LAST PATH I187
R 1
J 0
(-9150 5725);
DISPLAY 0.978723 (-9150 5725);
PAINT WHITE (-9150 5725);
DISPLAY INVISIBLE (-9150 5725);
FORCEADD Q_RES..2
(-1575 4225);
FORCEPROP 1 LAST LOCATION PR444
J 0
(-1520 4375);
DISPLAY 0.489362 (-1520 4375);
PAINT SKYBLUE (-1520 4375);
FORCEPROP 0 LAST $SEC 1
J 0
(-1500 4400);
DISPLAY 0.680851 (-1500 4400);
PAINT MONO (-1500 4400);
DISPLAY INVISIBLE (-1500 4400);
FORCEPROP 0 LAST CDS_SEC 1
J 0
(-1500 4400);
DISPLAY 1.021277 (-1500 4400);
DISPLAY INVISIBLE (-1500 4400);
FORCEPROP 1 LASTPIN (-1575 4325) $PN 1
J 0
(-1570 4287);
DISPLAY 0.787234 (-1570 4287);
PAINT MONO (-1570 4287);
DISPLAY INVISIBLE (-1570 4287);
FORCEPROP 1 LASTPIN (-1575 4125) $PN 2
J 0
(-1570 4135);
DISPLAY 0.787234 (-1570 4135);
PAINT MONO (-1570 4135);
DISPLAY INVISIBLE (-1570 4135);
FORCEPROP 1 LAST WATTAGE 1/16W
J 0
(-1525 4225);
DISPLAY 0.489362 (-1525 4225);
PAINT SKYBLUE (-1525 4225);
FORCEPROP 1 LAST MATERIAL CHIP
J 0
(-1525 4175);
DISPLAY 0.489362 (-1525 4175);
PAINT SKYBLUE (-1525 4175);
FORCEPROP 1 LAST TOLERANCE 1%
J 0
(-1520 4275);
DISPLAY 0.489362 (-1520 4275);
PAINT SKYBLUE (-1520 4275);
FORCEPROP 1 LAST VALUE 1K
J 0
(-1520 4325);
DISPLAY 0.489362 (-1520 4325);
PAINT SKYBLUE (-1520 4325);
FORCEPROP 1 LAST PART_NUMBER TMP_QCS21002FB24
J 0
(-1525 4125);
DISPLAY 0.489362 (-1525 4125);
PAINT SKYBLUE (-1525 4125);
FORCEPROP 1 LAST PACK_TYPE 0402LF
J 0
(-1525 4075);
DISPLAY 0.489362 (-1525 4075);
PAINT SKYBLUE (-1525 4075);
FORCEPROP 2 LAST CDS_LIB pure_quanta
J 0
(-1575 4225);
DISPLAY INVISIBLE (-1575 4225);
FORCEPROP 1 LAST PATH I188
J 0
(-1525 4400);
DISPLAY 0.978723 (-1525 4400);
PAINT WHITE (-1525 4400);
DISPLAY INVISIBLE (-1525 4400);
FORCEADD UNIVERSAL_GND..1
(-6300 775);
FORCEPROP 3 LASTPIN (-6300 825) SIG_NAME GND\g
J 0
(-6290 835);
DISPLAY 0.659574 (-6290 835);
PAINT MONO (-6290 835);
DISPLAY INVISIBLE (-6290 835);
FORCEPROP 2 LAST CDS_LIB pure_quanta_power
J 0
(-6300 775);
PAINT MONO (-6300 775);
DISPLAY INVISIBLE (-6300 775);
FORCEPROP 1 LAST PATH I19
J 0
(-6225 775);
DISPLAY 0.872340 (-6225 775);
PAINT AQUA (-6225 775);
DISPLAY INVISIBLE (-6225 775);
FORCEPROP 1 LAST HDL_POWER GND
J 1
(-6275 700);
DISPLAY 0.872340 (-6275 700);
PAINT GREEN (-6275 700);
DISPLAY INVISIBLE (-6275 700);
FORCEADD Q_RES..2
R 2
(-8875 1000);
FORCEPROP 1 LAST LOCATION PR77
J 2
(-8920 1125);
DISPLAY 0.489362 (-8920 1125);
PAINT SKYBLUE (-8920 1125);
FORCEPROP 0 LAST $SEC 1
J 0
(-8900 1175);
DISPLAY 0.680851 (-8900 1175);
PAINT MONO (-8900 1175);
DISPLAY INVISIBLE (-8900 1175);
FORCEPROP 0 LAST CDS_SEC 1
J 0
(-8900 1175);
DISPLAY 1.021277 (-8900 1175);
DISPLAY INVISIBLE (-8900 1175);
FORCEPROP 1 LASTPIN (-8875 1100) $PN 1
J 2
(-8880 1062);
DISPLAY 0.489362 (-8880 1062);
PAINT MONO (-8880 1062);
FORCEPROP 1 LASTPIN (-8875 900) $PN 2
J 2
(-8880 910);
DISPLAY 0.489362 (-8880 910);
PAINT MONO (-8880 910);
FORCEPROP 1 LAST WATTAGE 1/16W
J 2
(-8915 975);
DISPLAY 0.489362 (-8915 975);
PAINT SKYBLUE (-8915 975);
FORCEPROP 1 LAST MATERIAL EMPTY
J 2
(-8915 925);
DISPLAY 0.489362 (-8915 925);
PAINT RED (-8915 925);
FORCEPROP 1 LAST TOLERANCE 1%
J 2
(-8920 1025);
DISPLAY 0.489362 (-8920 1025);
PAINT SKYBLUE (-8920 1025);
FORCEPROP 1 LAST VALUE 8.87K
J 2
(-8920 1075);
DISPLAY 0.489362 (-8920 1075);
PAINT SKYBLUE (-8920 1075);
FORCEPROP 1 LAST PART_NUMBER CS28872FB01
J 2
(-8915 875);
DISPLAY 0.489362 (-8915 875);
PAINT SKYBLUE (-8915 875);
FORCEPROP 1 LAST PACK_TYPE 0402LF
J 2
(-8915 825);
DISPLAY 0.489362 (-8915 825);
PAINT SKYBLUE (-8915 825);
FORCEPROP 2 LAST CDS_LIB pure_quanta
J 2
(-8875 1000);
DISPLAY INVISIBLE (-8875 1000);
FORCEPROP 1 LAST PATH I2
J 2
(-8925 1175);
DISPLAY 0.978723 (-8925 1175);
PAINT WHITE (-8925 1175);
DISPLAY INVISIBLE (-8925 1175);
FORCEADD ISL99390FRZTR5935..1
(-6925 4450);
FORCEPROP 1 LAST LOCATION PU13
J 0
(-7225 5325);
DISPLAY 0.489362 (-7225 5325);
PAINT SKYBLUE (-7225 5325);
FORCEPROP 0 LAST $SEC 1
J 0
(-7225 5500);
DISPLAY 0.680851 (-7225 5500);
PAINT MONO (-7225 5500);
DISPLAY INVISIBLE (-7225 5500);
FORCEPROP 2 LAST CDS_SEC 1
J 0
(-7225 5500);
DISPLAY 1.021277 (-7225 5500);
DISPLAY INVISIBLE (-7225 5500);
FORCEPROP 0 LASTPIN (-6525 4000) $PN 2
J 0
(-6515 4010);
DISPLAY 0.489362 (-6515 4010);
PAINT MONO (-6515 4010);
FORCEPROP 0 LASTPIN (-6525 4800) $PN 33
J 0
(-6515 4810);
DISPLAY 0.489362 (-6515 4810);
PAINT MONO (-6515 4810);
FORCEPROP 0 LASTPIN (-7375 4200) $PN 31
J 2
(-7385 4210);
DISPLAY 0.489362 (-7385 4210);
PAINT MONO (-7385 4210);
FORCEPROP 0 LASTPIN (-7375 4600) $PN 35
J 2
(-7385 4610);
DISPLAY 0.489362 (-7385 4610);
PAINT MONO (-7385 4610);
FORCEPROP 0 LASTPIN (-6525 4150) $PN 6
J 0
(-6515 4160);
DISPLAY 0.489362 (-6515 4160);
PAINT MONO (-6515 4160);
FORCEPROP 0 LASTPIN (-6525 4100) $PN 41
J 0
(-6515 4110);
DISPLAY 0.489362 (-6515 4110);
PAINT MONO (-6515 4110);
FORCEPROP 0 LASTPIN (-7375 4450) $PN 38
J 2
(-7385 4460);
DISPLAY 0.489362 (-7385 4460);
PAINT MONO (-7385 4460);
FORCEPROP 0 LASTPIN (-7375 4150) $PN 37
J 2
(-7385 4160);
DISPLAY 0.489362 (-7385 4160);
PAINT MONO (-7385 4160);
FORCEPROP 0 LASTPIN (-6525 3950) $PN 5
J 0
(-6515 3960);
DISPLAY 0.489362 (-6515 3960);
PAINT MONO (-6515 3960);
FORCEPROP 0 LASTPIN (-6525 3900) $PN 7_9-20_24
J 0
(-6515 3910);
DISPLAY 0.489362 (-6515 3910);
PAINT MONO (-6515 3910);
FORCEPROP 0 LASTPIN (-6525 3850) $PN 40
J 0
(-6515 3860);
DISPLAY 0.489362 (-6515 3860);
PAINT MONO (-6515 3860);
FORCEPROP 0 LASTPIN (-6525 4550) $PN 32
J 0
(-6515 4560);
DISPLAY 0.489362 (-6515 4560);
PAINT MONO (-6515 4560);
FORCEPROP 0 LASTPIN (-7375 5100) $PN 4
J 2
(-7385 5110);
DISPLAY 0.489362 (-7385 5110);
PAINT MONO (-7385 5110);
FORCEPROP 0 LASTPIN (-7375 3850) $PN 34
J 2
(-7385 3860);
DISPLAY 0.489362 (-7385 3860);
PAINT MONO (-7385 3860);
FORCEPROP 0 LASTPIN (-7375 4350) $PN 39
J 2
(-7385 4360);
DISPLAY 0.489362 (-7385 4360);
PAINT MONO (-7385 4360);
FORCEPROP 0 LASTPIN (-6525 4450) $PN 10_19
J 0
(-6515 4460);
DISPLAY 0.489362 (-6515 4460);
PAINT MONO (-6515 4460);
FORCEPROP 0 LASTPIN (-7375 3950) $PN 36
J 2
(-7385 3960);
DISPLAY 0.489362 (-7385 3960);
PAINT MONO (-7385 3960);
FORCEPROP 0 LASTPIN (-7375 4800) $PN 3
J 2
(-7385 4810);
DISPLAY 0.489362 (-7385 4810);
PAINT MONO (-7385 4810);
FORCEPROP 0 LASTPIN (-6525 5100) $PN 25_29
J 0
(-6515 5110);
DISPLAY 0.489362 (-6515 5110);
PAINT MONO (-6515 5110);
FORCEPROP 0 LASTPIN (-6525 5050) $PN 30
J 0
(-6515 5060);
DISPLAY 0.489362 (-6515 5060);
PAINT MONO (-6515 5060);
FORCEPROP 0 LASTPIN (-6525 4200) $PN 1
J 0
(-6515 4210);
DISPLAY 0.489362 (-6515 4210);
PAINT MONO (-6515 4210);
FORCEPROP 2 LAST PART_TYPE SMLF
J 0
(-7225 5450);
DISPLAY 0.808511 (-7225 5450);
FORCEPROP 1 LAST MATERIAL IC
J 0
(-7225 5175);
DISPLAY 0.489362 (-7225 5175);
PAINT SKYBLUE (-7225 5175);
FORCEPROP 1 LAST PART_NUMBER AL099390004
J 0
(-7225 5250);
DISPLAY 0.489362 (-7225 5250);
PAINT SKYBLUE (-7225 5250);
FORCEPROP 2 LAST VALUE ISL99390FRZ-TR5935
J 0
(-7225 5400);
DISPLAY 0.489362 (-7225 5400);
PAINT SKYBLUE (-7225 5400);
FORCEPROP 2 LAST CDS_LIB pure_quanta
J 0
(-6925 4450);
DISPLAY INVISIBLE (-6925 4450);
FORCEPROP 1 LAST NEEDS_NO_SIZE TRUE
J 0
(-6925 4450);
DISPLAY 0.723404 (-6925 4450);
PAINT GREEN (-6925 4450);
DISPLAY INVISIBLE (-6925 4450);
FORCEPROP 1 LAST CDS_LMAN_SYM_OUTLINE -300,700,250,-650
J 0
(-6925 4450);
DISPLAY 0.468085 (-6925 4450);
PAINT GREEN (-6925 4450);
DISPLAY INVISIBLE (-6925 4450);
FORCEPROP 1 LAST PATH I21
J 0
(-6925 4450);
DISPLAY 0.723404 (-6925 4450);
PAINT GREEN (-6925 4450);
DISPLAY INVISIBLE (-6925 4450);
FORCEADD Q_CAP..1
(-5725 2400);
FORCEPROP 1 LAST LOCATION PC88_2
J 0
(-5675 2550);
DISPLAY 0.489362 (-5675 2550);
PAINT SKYBLUE (-5675 2550);
FORCEPROP 0 LAST $SEC 1
J 0
(-5675 2600);
DISPLAY 0.680851 (-5675 2600);
PAINT MONO (-5675 2600);
DISPLAY INVISIBLE (-5675 2600);
FORCEPROP 0 LAST CDS_SEC 1
J 0
(-5675 2600);
DISPLAY 1.021277 (-5675 2600);
DISPLAY INVISIBLE (-5675 2600);
FORCEPROP 1 LASTPIN (-5725 2500) $PN 1
J 0
(-5715 2480);
DISPLAY 0.489362 (-5715 2480);
PAINT MONO (-5715 2480);
FORCEPROP 1 LASTPIN (-5725 2300) $PN 2
J 0
(-5715 2280);
DISPLAY 0.489362 (-5715 2280);
PAINT MONO (-5715 2280);
FORCEPROP 1 LAST TOLERANCE 10%
J 0
(-5675 2400);
DISPLAY 0.489362 (-5675 2400);
PAINT SKYBLUE (-5675 2400);
FORCEPROP 1 LAST VALUE 1UF
J 0
(-5675 2500);
DISPLAY 0.489362 (-5675 2500);
PAINT SKYBLUE (-5675 2500);
FORCEPROP 1 LAST VOLTAGE 25V
J 0
(-5675 2450);
DISPLAY 0.489362 (-5675 2450);
PAINT SKYBLUE (-5675 2450);
FORCEPROP 1 LAST MATERIAL X6S
J 0
(-5675 2350);
DISPLAY 0.489362 (-5675 2350);
PAINT SKYBLUE (-5675 2350);
FORCEPROP 1 LAST PACK_TYPE C0402
J 0
(-5675 2300);
DISPLAY 0.489362 (-5675 2300);
PAINT SKYBLUE (-5675 2300);
FORCEPROP 1 LAST PART_NUMBER CH5104KEB02
J 0
(-5675 2250);
DISPLAY 0.489362 (-5675 2250);
PAINT SKYBLUE (-5675 2250);
FORCEPROP 2 LAST CDS_LIB pure_quanta
J 0
(-5725 2400);
DISPLAY INVISIBLE (-5725 2400);
FORCEPROP 1 LAST PATH I23
J 0
(-5675 2550);
DISPLAY 0.978723 (-5675 2550);
PAINT WHITE (-5675 2550);
DISPLAY INVISIBLE (-5675 2550);
FORCEADD Q_CAP..1
(-5325 2400);
FORCEPROP 1 LAST LOCATION PC90_2
J 0
(-5275 2550);
DISPLAY 0.489362 (-5275 2550);
PAINT SKYBLUE (-5275 2550);
FORCEPROP 0 LAST $SEC 1
J 0
(-5275 2600);
DISPLAY 0.680851 (-5275 2600);
PAINT MONO (-5275 2600);
DISPLAY INVISIBLE (-5275 2600);
FORCEPROP 0 LAST CDS_SEC 1
J 0
(-5275 2600);
DISPLAY 1.021277 (-5275 2600);
DISPLAY INVISIBLE (-5275 2600);
FORCEPROP 1 LASTPIN (-5325 2500) $PN 1
J 0
(-5315 2480);
DISPLAY 0.489362 (-5315 2480);
PAINT MONO (-5315 2480);
FORCEPROP 1 LASTPIN (-5325 2300) $PN 2
J 0
(-5315 2280);
DISPLAY 0.489362 (-5315 2280);
PAINT MONO (-5315 2280);
FORCEPROP 1 LAST PART_NUMBER CH6104KEA00
J 0
(-5275 2250);
DISPLAY 0.489362 (-5275 2250);
PAINT SKYBLUE (-5275 2250);
FORCEPROP 1 LAST MATERIAL X6S
J 0
(-5275 2350);
DISPLAY 0.489362 (-5275 2350);
PAINT SKYBLUE (-5275 2350);
FORCEPROP 1 LAST TOLERANCE 10%
J 0
(-5275 2400);
DISPLAY 0.489362 (-5275 2400);
PAINT SKYBLUE (-5275 2400);
FORCEPROP 1 LAST VALUE 10UF
J 0
(-5275 2500);
DISPLAY 0.489362 (-5275 2500);
PAINT SKYBLUE (-5275 2500);
FORCEPROP 1 LAST VOLTAGE 25V
J 0
(-5275 2450);
DISPLAY 0.489362 (-5275 2450);
PAINT SKYBLUE (-5275 2450);
FORCEPROP 1 LAST PACK_TYPE C0805
J 0
(-5275 2300);
DISPLAY 0.489362 (-5275 2300);
PAINT SKYBLUE (-5275 2300);
FORCEPROP 2 LAST CDS_LIB pure_quanta
J 0
(-5325 2400);
DISPLAY INVISIBLE (-5325 2400);
FORCEPROP 1 LAST PATH I24
J 0
(-5275 2550);
DISPLAY 0.978723 (-5275 2550);
PAINT WHITE (-5275 2550);
DISPLAY INVISIBLE (-5275 2550);
FORCEADD UNIVERSAL_GND..1
(-6275 3725);
FORCEPROP 3 LASTPIN (-6275 3775) SIG_NAME GND\g
J 0
(-6265 3785);
DISPLAY 0.659574 (-6265 3785);
PAINT MONO (-6265 3785);
DISPLAY INVISIBLE (-6265 3785);
FORCEPROP 2 LAST CDS_LIB pure_quanta_power
J 0
(-6275 3725);
PAINT MONO (-6275 3725);
DISPLAY INVISIBLE (-6275 3725);
FORCEPROP 1 LAST PATH I25
J 0
(-6200 3725);
DISPLAY 0.872340 (-6200 3725);
PAINT AQUA (-6200 3725);
DISPLAY INVISIBLE (-6200 3725);
FORCEPROP 1 LAST HDL_POWER GND
J 1
(-6250 3650);
DISPLAY 0.872340 (-6250 3650);
PAINT GREEN (-6250 3650);
DISPLAY INVISIBLE (-6250 3650);
FORCEADD UNIVERSAL_GND..1
(-9350 3875);
FORCEPROP 3 LASTPIN (-9350 3925) SIG_NAME GND\g
J 0
(-9340 3935);
DISPLAY 0.659574 (-9340 3935);
PAINT MONO (-9340 3935);
DISPLAY INVISIBLE (-9340 3935);
FORCEPROP 2 LAST CDS_LIB pure_quanta_power
J 0
(-9350 3875);
PAINT MONO (-9350 3875);
DISPLAY INVISIBLE (-9350 3875);
FORCEPROP 1 LAST PATH I26
J 0
(-9275 3875);
DISPLAY 0.872340 (-9275 3875);
PAINT AQUA (-9275 3875);
DISPLAY INVISIBLE (-9275 3875);
FORCEPROP 1 LAST HDL_POWER GND
J 1
(-9325 3800);
DISPLAY 0.872340 (-9325 3800);
PAINT GREEN (-9325 3800);
DISPLAY INVISIBLE (-9325 3800);
FORCEADD OFFPAGE..1
(-8275 4350);
FORCEPROP 2 LAST $XR5 182 
J 0
(-9127 4350);
DISPLAY 0.638298 (-9127 4350);
PAINT MONO (-9127 4350);
FORCEPROP 2 LAST $XR4 181 
J 0
(-9007 4350);
DISPLAY 0.638298 (-9007 4350);
PAINT MONO (-9007 4350);
FORCEPROP 2 LAST $XR3 179 
J 0
(-8887 4350);
DISPLAY 0.638298 (-8887 4350);
PAINT MONO (-8887 4350);
FORCEPROP 2 LAST $XR2 178 
J 0
(-8767 4350);
DISPLAY 0.638298 (-8767 4350);
PAINT MONO (-8767 4350);
FORCEPROP 2 LAST $XR1 177 
J 0
(-8647 4350);
DISPLAY 0.638298 (-8647 4350);
PAINT MONO (-8647 4350);
FORCEPROP 2 LAST $XR0 176 
J 0
(-8527 4350);
DISPLAY 0.638298 (-8527 4350);
PAINT MONO (-8527 4350);
FORCEPROP 2 LAST PATH I27
J 0
(-8525 4400);
DISPLAY 1.021277 (-8525 4400);
DISPLAY INVISIBLE (-8525 4400);
FORCEPROP 2 LAST CDS_LIB standard
J 0
(-8275 4350);
DISPLAY INVISIBLE (-8275 4350);
FORCEPROP 1 LAST OFFPAGE TRUE
J 0
(-7950 4225);
DISPLAY 0.872340 (-7950 4225);
PAINT GREEN (-7950 4225);
DISPLAY INVISIBLE (-7950 4225);
FORCEPROP 1 LAST COMMENT_BODY TRUE
J 0
(-8150 4250);
DISPLAY 0.872340 (-8150 4250);
PAINT GREEN (-8150 4250);
DISPLAY INVISIBLE (-8150 4250);
FORCEADD OFFPAGE..5
(-8275 4450);
FORCEPROP 2 LAST $XR0 176 
J 0
(-8530 4450);
DISPLAY 0.638298 (-8530 4450);
PAINT MONO (-8530 4450);
FORCEPROP 2 LAST PATH I28
J 0
(-8550 4500);
DISPLAY 1.021277 (-8550 4500);
DISPLAY INVISIBLE (-8550 4500);
FORCEPROP 2 LAST CDS_LIB standard
J 0
(-8275 4450);
DISPLAY INVISIBLE (-8275 4450);
FORCEPROP 1 LAST OFFPAGE TRUE
J 0
(-7950 4325);
DISPLAY 0.872340 (-7950 4325);
PAINT GREEN (-7950 4325);
DISPLAY INVISIBLE (-7950 4325);
FORCEPROP 1 LAST COMMENT_BODY TRUE
J 0
(-8175 4375);
DISPLAY 0.872340 (-8175 4375);
PAINT GREEN (-8175 4375);
DISPLAY INVISIBLE (-8175 4375);
FORCEADD OFFPAGE..1
(-8325 900);
FORCEPROP 2 LAST $XR0 176 
J 0
(-8577 900);
DISPLAY 0.638298 (-8577 900);
PAINT MONO (-8577 900);
FORCEPROP 2 LAST PATH I3
J 0
(-8575 950);
DISPLAY 1.021277 (-8575 950);
DISPLAY INVISIBLE (-8575 950);
FORCEPROP 2 LAST CDS_LIB standard
J 0
(-8325 900);
DISPLAY INVISIBLE (-8325 900);
FORCEPROP 1 LAST COMMENT_BODY TRUE
J 0
(-8200 800);
DISPLAY 0.872340 (-8200 800);
PAINT GREEN (-8200 800);
DISPLAY INVISIBLE (-8200 800);
FORCEPROP 1 LAST OFFPAGE TRUE
J 0
(-8000 775);
DISPLAY 0.872340 (-8000 775);
PAINT GREEN (-8000 775);
DISPLAY INVISIBLE (-8000 775);
FORCEADD UNIVERSAL_GND..1
(-9475 900);
FORCEPROP 3 LASTPIN (-9475 950) SIG_NAME GND\g
J 0
(-9465 960);
DISPLAY 0.659574 (-9465 960);
PAINT MONO (-9465 960);
DISPLAY INVISIBLE (-9465 960);
FORCEPROP 2 LAST CDS_LIB pure_quanta_power
J 0
(-9475 900);
PAINT MONO (-9475 900);
DISPLAY INVISIBLE (-9475 900);
FORCEPROP 1 LAST PATH I4
J 0
(-9400 900);
DISPLAY 0.872340 (-9400 900);
PAINT AQUA (-9400 900);
DISPLAY INVISIBLE (-9400 900);
FORCEPROP 1 LAST HDL_POWER GND
J 1
(-9450 825);
DISPLAY 0.872340 (-9450 825);
PAINT GREEN (-9450 825);
DISPLAY INVISIBLE (-9450 825);
FORCEADD Q_CAP..1
(-5750 5350);
FORCEPROP 1 LAST LOCATION PC87_1
J 0
(-5700 5500);
DISPLAY 0.489362 (-5700 5500);
PAINT SKYBLUE (-5700 5500);
FORCEPROP 0 LAST $SEC 1
J 0
(-5700 5550);
DISPLAY 0.680851 (-5700 5550);
PAINT MONO (-5700 5550);
DISPLAY INVISIBLE (-5700 5550);
FORCEPROP 0 LAST CDS_SEC 1
J 0
(-5700 5550);
DISPLAY 1.021277 (-5700 5550);
DISPLAY INVISIBLE (-5700 5550);
FORCEPROP 1 LASTPIN (-5750 5450) $PN 1
J 0
(-5740 5430);
DISPLAY 0.489362 (-5740 5430);
PAINT MONO (-5740 5430);
FORCEPROP 1 LASTPIN (-5750 5250) $PN 2
J 0
(-5740 5230);
DISPLAY 0.489362 (-5740 5230);
PAINT MONO (-5740 5230);
FORCEPROP 1 LAST TOLERANCE 10%
J 0
(-5700 5350);
DISPLAY 0.489362 (-5700 5350);
PAINT SKYBLUE (-5700 5350);
FORCEPROP 1 LAST MATERIAL X6S
J 0
(-5700 5300);
DISPLAY 0.489362 (-5700 5300);
PAINT SKYBLUE (-5700 5300);
FORCEPROP 1 LAST VALUE 1UF
J 0
(-5700 5450);
DISPLAY 0.489362 (-5700 5450);
PAINT SKYBLUE (-5700 5450);
FORCEPROP 1 LAST PART_NUMBER CH5104KEB02
J 0
(-5700 5200);
DISPLAY 0.489362 (-5700 5200);
PAINT SKYBLUE (-5700 5200);
FORCEPROP 1 LAST VOLTAGE 25V
J 0
(-5700 5400);
DISPLAY 0.489362 (-5700 5400);
PAINT SKYBLUE (-5700 5400);
FORCEPROP 1 LAST PACK_TYPE C0402
J 0
(-5700 5250);
DISPLAY 0.489362 (-5700 5250);
PAINT SKYBLUE (-5700 5250);
FORCEPROP 2 LAST CDS_LIB pure_quanta
J 0
(-5750 5350);
DISPLAY INVISIBLE (-5750 5350);
FORCEPROP 1 LAST PATH I41
J 0
(-5700 5500);
DISPLAY 0.978723 (-5700 5500);
PAINT WHITE (-5700 5500);
DISPLAY INVISIBLE (-5700 5500);
FORCEADD Q_CAP..1
(-4925 2400);
FORCEPROP 1 LAST LOCATION PC93_2
J 0
(-4875 2550);
DISPLAY 0.489362 (-4875 2550);
PAINT SKYBLUE (-4875 2550);
FORCEPROP 0 LAST $SEC 1
J 0
(-4875 2600);
DISPLAY 0.680851 (-4875 2600);
PAINT MONO (-4875 2600);
DISPLAY INVISIBLE (-4875 2600);
FORCEPROP 0 LAST CDS_SEC 1
J 0
(-4875 2600);
DISPLAY 1.021277 (-4875 2600);
DISPLAY INVISIBLE (-4875 2600);
FORCEPROP 1 LASTPIN (-4925 2500) $PN 1
J 0
(-4915 2480);
DISPLAY 0.489362 (-4915 2480);
PAINT MONO (-4915 2480);
FORCEPROP 1 LASTPIN (-4925 2300) $PN 2
J 0
(-4915 2280);
DISPLAY 0.489362 (-4915 2280);
PAINT MONO (-4915 2280);
FORCEPROP 1 LAST PART_NUMBER CH6104KEA00
J 0
(-4875 2250);
DISPLAY 0.489362 (-4875 2250);
PAINT SKYBLUE (-4875 2250);
FORCEPROP 1 LAST VALUE 10UF
J 0
(-4875 2500);
DISPLAY 0.489362 (-4875 2500);
PAINT SKYBLUE (-4875 2500);
FORCEPROP 1 LAST TOLERANCE 10%
J 0
(-4875 2400);
DISPLAY 0.489362 (-4875 2400);
PAINT SKYBLUE (-4875 2400);
FORCEPROP 1 LAST VOLTAGE 25V
J 0
(-4875 2450);
DISPLAY 0.489362 (-4875 2450);
PAINT SKYBLUE (-4875 2450);
FORCEPROP 1 LAST PACK_TYPE C0805
J 0
(-4875 2300);
DISPLAY 0.489362 (-4875 2300);
PAINT SKYBLUE (-4875 2300);
FORCEPROP 1 LAST MATERIAL X6S
J 0
(-4875 2350);
DISPLAY 0.489362 (-4875 2350);
PAINT SKYBLUE (-4875 2350);
FORCEPROP 2 LAST CDS_LIB pure_quanta
J 0
(-4925 2400);
DISPLAY INVISIBLE (-4925 2400);
FORCEPROP 1 LAST PATH I46
J 0
(-4875 2550);
DISPLAY 0.978723 (-4875 2550);
PAINT WHITE (-4875 2550);
DISPLAY INVISIBLE (-4875 2550);
FORCEADD Q_CAP..1
(-4550 2400);
FORCEPROP 1 LAST LOCATION PC96_2
J 0
(-4500 2550);
DISPLAY 0.489362 (-4500 2550);
PAINT SKYBLUE (-4500 2550);
FORCEPROP 0 LAST $SEC 1
J 0
(-4500 2600);
DISPLAY 0.680851 (-4500 2600);
PAINT MONO (-4500 2600);
DISPLAY INVISIBLE (-4500 2600);
FORCEPROP 0 LAST CDS_SEC 1
J 0
(-4500 2600);
DISPLAY 1.021277 (-4500 2600);
DISPLAY INVISIBLE (-4500 2600);
FORCEPROP 1 LASTPIN (-4550 2500) $PN 1
J 0
(-4540 2480);
DISPLAY 0.489362 (-4540 2480);
PAINT MONO (-4540 2480);
FORCEPROP 1 LASTPIN (-4550 2300) $PN 2
J 0
(-4540 2280);
DISPLAY 0.489362 (-4540 2280);
PAINT MONO (-4540 2280);
FORCEPROP 1 LAST MATERIAL X6S
J 0
(-4500 2350);
DISPLAY 0.489362 (-4500 2350);
PAINT SKYBLUE (-4500 2350);
FORCEPROP 1 LAST PACK_TYPE C0805
J 0
(-4500 2300);
DISPLAY 0.489362 (-4500 2300);
PAINT SKYBLUE (-4500 2300);
FORCEPROP 1 LAST PART_NUMBER CH6104KEA00
J 0
(-4500 2250);
DISPLAY 0.489362 (-4500 2250);
PAINT SKYBLUE (-4500 2250);
FORCEPROP 1 LAST TOLERANCE 10%
J 0
(-4500 2400);
DISPLAY 0.489362 (-4500 2400);
PAINT SKYBLUE (-4500 2400);
FORCEPROP 1 LAST VALUE 10UF
J 0
(-4500 2500);
DISPLAY 0.489362 (-4500 2500);
PAINT SKYBLUE (-4500 2500);
FORCEPROP 1 LAST VOLTAGE 25V
J 0
(-4500 2450);
DISPLAY 0.489362 (-4500 2450);
PAINT SKYBLUE (-4500 2450);
FORCEPROP 2 LAST CDS_LIB pure_quanta
J 0
(-4550 2400);
DISPLAY INVISIBLE (-4550 2400);
FORCEPROP 1 LAST PATH I47
J 0
(-4500 2550);
DISPLAY 0.978723 (-4500 2550);
PAINT WHITE (-4500 2550);
DISPLAY INVISIBLE (-4500 2550);
FORCEADD UNIVERSAL_GND..1
(-4550 2025);
FORCEPROP 3 LASTPIN (-4550 2075) SIG_NAME GND\g
J 0
(-4540 2085);
DISPLAY 0.659574 (-4540 2085);
PAINT MONO (-4540 2085);
DISPLAY INVISIBLE (-4540 2085);
FORCEPROP 2 LAST CDS_LIB pure_quanta_power
J 0
(-4550 2025);
PAINT MONO (-4550 2025);
DISPLAY INVISIBLE (-4550 2025);
FORCEPROP 1 LAST PATH I48
J 0
(-4475 2025);
DISPLAY 0.872340 (-4475 2025);
PAINT AQUA (-4475 2025);
DISPLAY INVISIBLE (-4475 2025);
FORCEPROP 1 LAST HDL_POWER GND
J 1
(-4525 1950);
DISPLAY 0.872340 (-4525 1950);
PAINT GREEN (-4525 1950);
DISPLAY INVISIBLE (-4525 1950);
FORCEADD VCC_CORE..1
(-4550 2750);
FORCEPROP 3 LASTPIN (-4550 2700) SIG_NAME SW_P12V_STBY_PVDDCR_CPU1_P0_FLT\g
J 0
(-4540 2710);
DISPLAY 0.659574 (-4540 2710);
PAINT MONO (-4540 2710);
DISPLAY INVISIBLE (-4540 2710);
FORCEPROP 1 LAST HDL_POWER SW_P12V_STBY_PVDDCR_CPU1_P0_FLT
J 1
(-4550 2800);
DISPLAY 0.489362 (-4550 2800);
PAINT GREEN (-4550 2800);
FORCEPROP 2 LAST CDS_LIB pure_quanta_power
J 0
(-4550 2750);
DISPLAY INVISIBLE (-4550 2750);
FORCEPROP 1 LAST PATH I49
J 0
(-4500 2775);
DISPLAY 0.872340 (-4500 2775);
PAINT AQUA (-4500 2775);
DISPLAY INVISIBLE (-4500 2775);
FORCEADD OFFPAGE..5
(-8325 1000);
FORCEPROP 2 LAST $XR3 176 
J 0
(-8730 964);
DISPLAY 0.638298 (-8730 964);
PAINT MONO (-8730 964);
FORCEPROP 2 LAST $XR2 179 
J 0
(-8610 964);
DISPLAY 0.638298 (-8610 964);
PAINT MONO (-8610 964);
FORCEPROP 2 LAST $XR1 178 
J 0
(-8730 1000);
DISPLAY 0.638298 (-8730 1000);
PAINT MONO (-8730 1000);
FORCEPROP 2 LAST $XR0 177 
J 0
(-8610 1000);
DISPLAY 0.638298 (-8610 1000);
PAINT MONO (-8610 1000);
FORCEPROP 1 LAST COMMENT_BODY TRUE
J 0
(-8225 925);
DISPLAY 0.872340 (-8225 925);
PAINT GREEN (-8225 925);
DISPLAY INVISIBLE (-8225 925);
FORCEPROP 2 LAST CDS_LIB standard
J 0
(-8325 1000);
DISPLAY INVISIBLE (-8325 1000);
FORCEPROP 2 LAST PATH I5
J 0
(-8575 1075);
DISPLAY 1.021277 (-8575 1075);
DISPLAY INVISIBLE (-8575 1075);
FORCEPROP 1 LAST OFFPAGE TRUE
J 0
(-8000 875);
DISPLAY 0.872340 (-8000 875);
PAINT GREEN (-8000 875);
DISPLAY INVISIBLE (-8000 875);
FORCEADD OFFPAGE..1
(-8325 1400);
FORCEPROP 2 LAST $XR5 182 
J 0
(-9177 1400);
DISPLAY 0.638298 (-9177 1400);
PAINT MONO (-9177 1400);
FORCEPROP 2 LAST $XR4 181 
J 0
(-9057 1400);
DISPLAY 0.638298 (-9057 1400);
PAINT MONO (-9057 1400);
FORCEPROP 2 LAST $XR3 179 
J 0
(-8937 1400);
DISPLAY 0.638298 (-8937 1400);
PAINT MONO (-8937 1400);
FORCEPROP 2 LAST $XR2 178 
J 0
(-8817 1400);
DISPLAY 0.638298 (-8817 1400);
PAINT MONO (-8817 1400);
FORCEPROP 2 LAST $XR1 177 
J 0
(-8697 1400);
DISPLAY 0.638298 (-8697 1400);
PAINT MONO (-8697 1400);
FORCEPROP 2 LAST $XR0 176 
J 0
(-8577 1400);
DISPLAY 0.638298 (-8577 1400);
PAINT MONO (-8577 1400);
FORCEPROP 2 LAST PATH I6
J 0
(-8575 1450);
DISPLAY 1.021277 (-8575 1450);
DISPLAY INVISIBLE (-8575 1450);
FORCEPROP 2 LAST CDS_LIB standard
J 0
(-8325 1400);
DISPLAY INVISIBLE (-8325 1400);
FORCEPROP 1 LAST COMMENT_BODY TRUE
J 0
(-8200 1300);
DISPLAY 0.872340 (-8200 1300);
PAINT GREEN (-8200 1300);
DISPLAY INVISIBLE (-8200 1300);
FORCEPROP 1 LAST OFFPAGE TRUE
J 0
(-8000 1275);
DISPLAY 0.872340 (-8000 1275);
PAINT GREEN (-8000 1275);
DISPLAY INVISIBLE (-8000 1275);
FORCEADD UNIVERSAL_GND..1
(-4350 4975);
FORCEPROP 3 LASTPIN (-4350 5025) SIG_NAME GND\g
J 0
(-4340 5035);
DISPLAY 0.659574 (-4340 5035);
PAINT MONO (-4340 5035);
DISPLAY INVISIBLE (-4340 5035);
FORCEPROP 2 LAST CDS_LIB pure_quanta_power
J 0
(-4350 4975);
PAINT MONO (-4350 4975);
DISPLAY INVISIBLE (-4350 4975);
FORCEPROP 1 LAST PATH I64
J 0
(-4275 4975);
DISPLAY 0.872340 (-4275 4975);
PAINT AQUA (-4275 4975);
DISPLAY INVISIBLE (-4275 4975);
FORCEPROP 1 LAST HDL_POWER GND
J 1
(-4325 4900);
DISPLAY 0.872340 (-4325 4900);
PAINT GREEN (-4325 4900);
DISPLAY INVISIBLE (-4325 4900);
FORCEADD Q_CAP..1
(-5350 5350);
FORCEPROP 1 LAST LOCATION PC89_1
J 0
(-5300 5500);
DISPLAY 0.489362 (-5300 5500);
PAINT SKYBLUE (-5300 5500);
FORCEPROP 0 LAST $SEC 1
J 0
(-5300 5550);
DISPLAY 0.680851 (-5300 5550);
PAINT MONO (-5300 5550);
DISPLAY INVISIBLE (-5300 5550);
FORCEPROP 0 LAST CDS_SEC 1
J 0
(-5300 5550);
DISPLAY 1.021277 (-5300 5550);
DISPLAY INVISIBLE (-5300 5550);
FORCEPROP 1 LASTPIN (-5350 5450) $PN 1
J 0
(-5340 5430);
DISPLAY 0.489362 (-5340 5430);
PAINT MONO (-5340 5430);
FORCEPROP 1 LASTPIN (-5350 5250) $PN 2
J 0
(-5340 5230);
DISPLAY 0.489362 (-5340 5230);
PAINT MONO (-5340 5230);
FORCEPROP 1 LAST PART_NUMBER CH6104KEA00
J 0
(-5300 5200);
DISPLAY 0.489362 (-5300 5200);
PAINT SKYBLUE (-5300 5200);
FORCEPROP 1 LAST MATERIAL X6S
J 0
(-5300 5300);
DISPLAY 0.489362 (-5300 5300);
PAINT SKYBLUE (-5300 5300);
FORCEPROP 1 LAST TOLERANCE 10%
J 0
(-5300 5350);
DISPLAY 0.489362 (-5300 5350);
PAINT SKYBLUE (-5300 5350);
FORCEPROP 1 LAST VALUE 10UF
J 0
(-5300 5450);
DISPLAY 0.489362 (-5300 5450);
PAINT SKYBLUE (-5300 5450);
FORCEPROP 1 LAST VOLTAGE 25V
J 0
(-5300 5400);
DISPLAY 0.489362 (-5300 5400);
PAINT SKYBLUE (-5300 5400);
FORCEPROP 1 LAST PACK_TYPE C0805
J 0
(-5300 5250);
DISPLAY 0.489362 (-5300 5250);
PAINT SKYBLUE (-5300 5250);
FORCEPROP 2 LAST CDS_LIB pure_quanta
J 0
(-5350 5350);
DISPLAY INVISIBLE (-5350 5350);
FORCEPROP 1 LAST PATH I65
J 0
(-5300 5500);
DISPLAY 0.978723 (-5300 5500);
PAINT WHITE (-5300 5500);
DISPLAY INVISIBLE (-5300 5500);
FORCEADD Q_CAP..1
(-4950 5350);
FORCEPROP 1 LAST LOCATION PC91_1
J 0
(-4900 5500);
DISPLAY 0.489362 (-4900 5500);
PAINT SKYBLUE (-4900 5500);
FORCEPROP 0 LAST $SEC 1
J 0
(-4900 5550);
DISPLAY 0.680851 (-4900 5550);
PAINT MONO (-4900 5550);
DISPLAY INVISIBLE (-4900 5550);
FORCEPROP 0 LAST CDS_SEC 1
J 0
(-4900 5550);
DISPLAY 1.021277 (-4900 5550);
DISPLAY INVISIBLE (-4900 5550);
FORCEPROP 1 LASTPIN (-4950 5450) $PN 1
J 0
(-4940 5430);
DISPLAY 0.489362 (-4940 5430);
PAINT MONO (-4940 5430);
FORCEPROP 1 LASTPIN (-4950 5250) $PN 2
J 0
(-4940 5230);
DISPLAY 0.489362 (-4940 5230);
PAINT MONO (-4940 5230);
FORCEPROP 1 LAST PART_NUMBER CH6104KEA00
J 0
(-4900 5200);
DISPLAY 0.489362 (-4900 5200);
PAINT SKYBLUE (-4900 5200);
FORCEPROP 1 LAST VALUE 10UF
J 0
(-4900 5450);
DISPLAY 0.489362 (-4900 5450);
PAINT SKYBLUE (-4900 5450);
FORCEPROP 1 LAST MATERIAL X6S
J 0
(-4900 5300);
DISPLAY 0.489362 (-4900 5300);
PAINT SKYBLUE (-4900 5300);
FORCEPROP 1 LAST TOLERANCE 10%
J 0
(-4900 5350);
DISPLAY 0.489362 (-4900 5350);
PAINT SKYBLUE (-4900 5350);
FORCEPROP 1 LAST VOLTAGE 25V
J 0
(-4900 5400);
DISPLAY 0.489362 (-4900 5400);
PAINT SKYBLUE (-4900 5400);
FORCEPROP 1 LAST PACK_TYPE C0805
J 0
(-4900 5250);
DISPLAY 0.489362 (-4900 5250);
PAINT SKYBLUE (-4900 5250);
FORCEPROP 2 LAST CDS_LIB pure_quanta
J 0
(-4950 5350);
DISPLAY INVISIBLE (-4950 5350);
FORCEPROP 1 LAST PATH I66
J 0
(-4900 5500);
DISPLAY 0.978723 (-4900 5500);
PAINT WHITE (-4900 5500);
DISPLAY INVISIBLE (-4900 5500);
FORCEADD Q_CAP..1
(-4575 5350);
FORCEPROP 1 LAST LOCATION PC95_1
J 0
(-4525 5500);
DISPLAY 0.489362 (-4525 5500);
PAINT SKYBLUE (-4525 5500);
FORCEPROP 0 LAST $SEC 1
J 0
(-4525 5550);
DISPLAY 0.680851 (-4525 5550);
PAINT MONO (-4525 5550);
DISPLAY INVISIBLE (-4525 5550);
FORCEPROP 0 LAST CDS_SEC 1
J 0
(-4525 5550);
DISPLAY 1.021277 (-4525 5550);
DISPLAY INVISIBLE (-4525 5550);
FORCEPROP 1 LASTPIN (-4575 5450) $PN 1
J 0
(-4565 5430);
DISPLAY 0.489362 (-4565 5430);
PAINT MONO (-4565 5430);
FORCEPROP 1 LASTPIN (-4575 5250) $PN 2
J 0
(-4565 5230);
DISPLAY 0.489362 (-4565 5230);
PAINT MONO (-4565 5230);
FORCEPROP 1 LAST VALUE 10UF
J 0
(-4525 5450);
DISPLAY 0.489362 (-4525 5450);
PAINT SKYBLUE (-4525 5450);
FORCEPROP 1 LAST PART_NUMBER CH6104KEA00
J 0
(-4525 5200);
DISPLAY 0.489362 (-4525 5200);
PAINT SKYBLUE (-4525 5200);
FORCEPROP 1 LAST MATERIAL X6S
J 0
(-4525 5300);
DISPLAY 0.489362 (-4525 5300);
PAINT SKYBLUE (-4525 5300);
FORCEPROP 1 LAST PACK_TYPE C0805
J 0
(-4525 5250);
DISPLAY 0.489362 (-4525 5250);
PAINT SKYBLUE (-4525 5250);
FORCEPROP 1 LAST TOLERANCE 10%
J 0
(-4525 5350);
DISPLAY 0.489362 (-4525 5350);
PAINT SKYBLUE (-4525 5350);
FORCEPROP 1 LAST VOLTAGE 25V
J 0
(-4525 5400);
DISPLAY 0.489362 (-4525 5400);
PAINT SKYBLUE (-4525 5400);
FORCEPROP 2 LAST CDS_LIB pure_quanta
J 0
(-4575 5350);
DISPLAY INVISIBLE (-4575 5350);
FORCEPROP 1 LAST PATH I67
J 0
(-4525 5500);
DISPLAY 0.978723 (-4525 5500);
PAINT WHITE (-4525 5500);
DISPLAY INVISIBLE (-4525 5500);
FORCEADD VCC_CORE..1
(-4350 5700);
FORCEPROP 3 LASTPIN (-4350 5650) SIG_NAME SW_P12V_STBY_PVDDCR_CPU1_P0_FLT\g
J 0
(-4340 5660);
DISPLAY 0.659574 (-4340 5660);
PAINT MONO (-4340 5660);
DISPLAY INVISIBLE (-4340 5660);
FORCEPROP 1 LAST HDL_POWER SW_P12V_STBY_PVDDCR_CPU1_P0_FLT
J 1
(-4350 5750);
DISPLAY 0.489362 (-4350 5750);
PAINT GREEN (-4350 5750);
FORCEPROP 2 LAST CDS_LIB pure_quanta_power
J 0
(-4350 5700);
DISPLAY INVISIBLE (-4350 5700);
FORCEPROP 1 LAST PATH I68
J 0
(-4300 5725);
DISPLAY 0.872340 (-4300 5725);
PAINT AQUA (-4300 5725);
DISPLAY INVISIBLE (-4300 5725);
FORCEADD VCC_CORE..1
(-3050 5700);
FORCEPROP 3 LASTPIN (-3050 5650) SIG_NAME P12V_STBY\g
J 0
(-3040 5660);
DISPLAY 0.659574 (-3040 5660);
PAINT MONO (-3040 5660);
DISPLAY INVISIBLE (-3040 5660);
FORCEPROP 1 LAST HDL_POWER P12V_STBY
J 1
(-3050 5750);
DISPLAY 0.489362 (-3050 5750);
PAINT GREEN (-3050 5750);
FORCEPROP 2 LAST CDS_LIB pure_quanta_power
J 0
(-3050 5700);
DISPLAY INVISIBLE (-3050 5700);
FORCEPROP 1 LAST PATH I73
J 0
(-3000 5725);
DISPLAY 0.872340 (-3000 5725);
PAINT AQUA (-3000 5725);
DISPLAY INVISIBLE (-3000 5725);
FORCEADD Q_CAPP..1
(-4150 5350);
FORCEPROP 1 LAST LOCATION PC101
J 0
(-4100 5475);
DISPLAY 0.489362 (-4100 5475);
PAINT SKYBLUE (-4100 5475);
FORCEPROP 0 LAST $SEC 1
J 0
(-4100 5525);
DISPLAY 0.680851 (-4100 5525);
PAINT MONO (-4100 5525);
DISPLAY INVISIBLE (-4100 5525);
FORCEPROP 0 LAST CDS_SEC 1
J 0
(-4100 5525);
DISPLAY 1.021277 (-4100 5525);
DISPLAY INVISIBLE (-4100 5525);
FORCEPROP 1 LASTPIN (-4150 5450) $PN 1
J 0
(-4140 5435);
DISPLAY 0.489362 (-4140 5435);
PAINT MONO (-4140 5435);
FORCEPROP 1 LASTPIN (-4150 5250) $PN 2
J 0
(-4140 5235);
DISPLAY 0.489362 (-4140 5235);
PAINT MONO (-4140 5235);
FORCEPROP 1 LAST PART_NUMBER CC72204MD02
J 0
(-4100 5175);
DISPLAY 0.489362 (-4100 5175);
PAINT SKYBLUE (-4100 5175);
FORCEPROP 1 LAST MATERIAL OSCON
J 0
(-4100 5275);
DISPLAY 0.489362 (-4100 5275);
PAINT SKYBLUE (-4100 5275);
FORCEPROP 1 LAST VOLTAGE 25V
J 0
(-4100 5325);
DISPLAY 0.489362 (-4100 5325);
PAINT SKYBLUE (-4100 5325);
FORCEPROP 1 LAST PACK_TYPE THLF
J 0
(-4100 5225);
DISPLAY 0.489362 (-4100 5225);
PAINT SKYBLUE (-4100 5225);
FORCEPROP 1 LAST TOLERANCE 20%
J 0
(-4100 5375);
DISPLAY 0.489362 (-4100 5375);
PAINT SKYBLUE (-4100 5375);
FORCEPROP 1 LAST VALUE 220UF
J 0
(-4100 5425);
DISPLAY 0.489362 (-4100 5425);
PAINT SKYBLUE (-4100 5425);
FORCEPROP 2 LAST CDS_LIB pure_quanta
J 0
(-4150 5350);
DISPLAY INVISIBLE (-4150 5350);
FORCEPROP 1 LAST PATH I74
J 0
(-4100 5500);
DISPLAY 0.978723 (-4100 5500);
DISPLAY INVISIBLE (-4100 5500);
FORCEADD Q_INDUCTOR..1
(-3350 5625);
FORCEPROP 1 LAST LOCATION PL12
J 0
(-3200 5625);
DISPLAY 0.489362 (-3200 5625);
PAINT SKYBLUE (-3200 5625);
FORCEPROP 2 LAST $SEC 1
J 0
(-3475 5900);
DISPLAY 0.680851 (-3475 5900);
PAINT MONO (-3475 5900);
DISPLAY INVISIBLE (-3475 5900);
FORCEPROP 0 LAST CDS_SEC 1
J 0
(-3375 5725);
DISPLAY 1.021277 (-3375 5725);
DISPLAY INVISIBLE (-3375 5725);
FORCEPROP 2 LASTPIN (-3450 5600) $PN 1
J 2
(-3460 5610);
DISPLAY 0.489362 (-3460 5610);
FORCEPROP 2 LASTPIN (-3250 5600) $PN 2
J 0
(-3240 5610);
DISPLAY 0.489362 (-3240 5610);
FORCEPROP 1 LAST PART_NUMBER CVA50^0MZ09
J 0
(-3475 5735);
DISPLAY 0.489362 (-3475 5735);
PAINT SKYBLUE (-3475 5735);
FORCEPROP 1 LAST MATERIAL IND
J 0
(-3475 5680);
DISPLAY 0.489362 (-3475 5680);
PAINT SKYBLUE (-3475 5680);
FORCEPROP 2 LAST VALUE 50NH/86A
J 0
(-3475 5800);
DISPLAY 0.489362 (-3475 5800);
PAINT SKYBLUE (-3475 5800);
FORCEPROP 2 LAST PACK_TYPE SMLF
J 0
(-3475 5850);
DISPLAY 0.489362 (-3475 5850);
PAINT SKYBLUE (-3475 5850);
FORCEPROP 2 LAST CDS_LIB pure_quanta
J 0
(-3350 5625);
PAINT MONO (-3350 5625);
DISPLAY INVISIBLE (-3350 5625);
FORCEPROP 1 LAST NEEDS_NO_SIZE TRUE
J 0
(-3350 5625);
DISPLAY 0.468085 (-3350 5625);
PAINT GREEN (-3350 5625);
DISPLAY INVISIBLE (-3350 5625);
FORCEPROP 1 LAST PATH I75
J 0
(-3275 5680);
DISPLAY 0.723404 (-3275 5680);
PAINT GREEN (-3275 5680);
DISPLAY INVISIBLE (-3275 5680);
FORCEADD Q_CAPP..1
(-3750 5350);
FORCEPROP 1 LAST LOCATION PC104
J 0
(-3700 5475);
DISPLAY 0.489362 (-3700 5475);
PAINT SKYBLUE (-3700 5475);
FORCEPROP 0 LAST $SEC 1
J 0
(-3700 5525);
DISPLAY 0.680851 (-3700 5525);
PAINT MONO (-3700 5525);
DISPLAY INVISIBLE (-3700 5525);
FORCEPROP 0 LAST CDS_SEC 1
J 0
(-3700 5525);
DISPLAY 1.021277 (-3700 5525);
DISPLAY INVISIBLE (-3700 5525);
FORCEPROP 1 LASTPIN (-3750 5450) $PN 1
J 0
(-3740 5435);
DISPLAY 0.489362 (-3740 5435);
PAINT MONO (-3740 5435);
FORCEPROP 1 LASTPIN (-3750 5250) $PN 2
J 0
(-3740 5235);
DISPLAY 0.489362 (-3740 5235);
PAINT MONO (-3740 5235);
FORCEPROP 1 LAST MATERIAL OSCON
J 0
(-3700 5275);
DISPLAY 0.489362 (-3700 5275);
PAINT SKYBLUE (-3700 5275);
FORCEPROP 1 LAST TOLERANCE 20%
J 0
(-3700 5375);
DISPLAY 0.489362 (-3700 5375);
PAINT SKYBLUE (-3700 5375);
FORCEPROP 1 LAST VALUE 220UF
J 0
(-3700 5425);
DISPLAY 0.489362 (-3700 5425);
PAINT SKYBLUE (-3700 5425);
FORCEPROP 1 LAST PART_NUMBER CC72204MD02
J 0
(-3700 5175);
DISPLAY 0.489362 (-3700 5175);
PAINT SKYBLUE (-3700 5175);
FORCEPROP 1 LAST VOLTAGE 25V
J 0
(-3700 5325);
DISPLAY 0.489362 (-3700 5325);
PAINT SKYBLUE (-3700 5325);
FORCEPROP 1 LAST PACK_TYPE THLF
J 0
(-3700 5225);
DISPLAY 0.489362 (-3700 5225);
PAINT SKYBLUE (-3700 5225);
FORCEPROP 2 LAST CDS_LIB pure_quanta
J 0
(-3750 5350);
DISPLAY INVISIBLE (-3750 5350);
FORCEPROP 1 LAST PATH I76
J 0
(-3700 5500);
DISPLAY 0.978723 (-3700 5500);
DISPLAY INVISIBLE (-3700 5500);
FORCEADD ISL99390FRZTR5935..1
(-6950 1500);
FORCEPROP 1 LAST LOCATION PU2
J 0
(-7250 2375);
DISPLAY 0.489362 (-7250 2375);
PAINT SKYBLUE (-7250 2375);
FORCEPROP 0 LAST $SEC 1
J 0
(-7250 2550);
DISPLAY 0.680851 (-7250 2550);
PAINT MONO (-7250 2550);
DISPLAY INVISIBLE (-7250 2550);
FORCEPROP 0 LAST CDS_SEC 1
J 0
(-7250 2550);
DISPLAY 1.021277 (-7250 2550);
DISPLAY INVISIBLE (-7250 2550);
FORCEPROP 0 LASTPIN (-6550 1050) $PN 2
J 0
(-6540 1060);
DISPLAY 0.489362 (-6540 1060);
PAINT MONO (-6540 1060);
FORCEPROP 0 LASTPIN (-6550 1850) $PN 33
J 0
(-6540 1860);
DISPLAY 0.489362 (-6540 1860);
PAINT MONO (-6540 1860);
FORCEPROP 0 LASTPIN (-7400 1250) $PN 31
J 2
(-7410 1260);
DISPLAY 0.489362 (-7410 1260);
PAINT MONO (-7410 1260);
FORCEPROP 0 LASTPIN (-7400 1650) $PN 35
J 2
(-7410 1660);
DISPLAY 0.489362 (-7410 1660);
PAINT MONO (-7410 1660);
FORCEPROP 0 LASTPIN (-6550 1200) $PN 6
J 0
(-6540 1210);
DISPLAY 0.489362 (-6540 1210);
PAINT MONO (-6540 1210);
FORCEPROP 0 LASTPIN (-6550 1150) $PN 41
J 0
(-6540 1160);
DISPLAY 0.489362 (-6540 1160);
PAINT MONO (-6540 1160);
FORCEPROP 0 LASTPIN (-7400 1500) $PN 38
J 2
(-7410 1510);
DISPLAY 0.489362 (-7410 1510);
PAINT MONO (-7410 1510);
FORCEPROP 0 LASTPIN (-7400 1200) $PN 37
J 2
(-7410 1210);
DISPLAY 0.489362 (-7410 1210);
PAINT MONO (-7410 1210);
FORCEPROP 0 LASTPIN (-6550 1000) $PN 5
J 0
(-6540 1010);
DISPLAY 0.489362 (-6540 1010);
PAINT MONO (-6540 1010);
FORCEPROP 0 LASTPIN (-6550 950) $PN 7_9-20_24
J 0
(-6540 960);
DISPLAY 0.489362 (-6540 960);
PAINT MONO (-6540 960);
FORCEPROP 0 LASTPIN (-6550 900) $PN 40
J 0
(-6540 910);
DISPLAY 0.489362 (-6540 910);
PAINT MONO (-6540 910);
FORCEPROP 0 LASTPIN (-6550 1600) $PN 32
J 0
(-6540 1610);
DISPLAY 0.489362 (-6540 1610);
PAINT MONO (-6540 1610);
FORCEPROP 0 LASTPIN (-7400 2150) $PN 4
J 2
(-7410 2160);
DISPLAY 0.489362 (-7410 2160);
PAINT MONO (-7410 2160);
FORCEPROP 0 LASTPIN (-7400 900) $PN 34
J 2
(-7410 910);
DISPLAY 0.489362 (-7410 910);
PAINT MONO (-7410 910);
FORCEPROP 0 LASTPIN (-7400 1400) $PN 39
J 2
(-7410 1410);
DISPLAY 0.489362 (-7410 1410);
PAINT MONO (-7410 1410);
FORCEPROP 0 LASTPIN (-6550 1500) $PN 10_19
J 0
(-6540 1510);
DISPLAY 0.489362 (-6540 1510);
PAINT MONO (-6540 1510);
FORCEPROP 0 LASTPIN (-7400 1000) $PN 36
J 2
(-7410 1010);
DISPLAY 0.489362 (-7410 1010);
PAINT MONO (-7410 1010);
FORCEPROP 0 LASTPIN (-7400 1850) $PN 3
J 2
(-7410 1860);
DISPLAY 0.489362 (-7410 1860);
PAINT MONO (-7410 1860);
FORCEPROP 0 LASTPIN (-6550 2150) $PN 25_29
J 0
(-6540 2160);
DISPLAY 0.489362 (-6540 2160);
PAINT MONO (-6540 2160);
FORCEPROP 0 LASTPIN (-6550 2100) $PN 30
J 0
(-6540 2110);
DISPLAY 0.489362 (-6540 2110);
PAINT MONO (-6540 2110);
FORCEPROP 0 LASTPIN (-6550 1250) $PN 1
J 0
(-6540 1260);
DISPLAY 0.489362 (-6540 1260);
PAINT MONO (-6540 1260);
FORCEPROP 2 LAST VALUE ISL99390FRZ-TR5935
J 0
(-7250 2450);
DISPLAY 0.489362 (-7250 2450);
PAINT SKYBLUE (-7250 2450);
FORCEPROP 2 LAST PART_TYPE SMLF
J 0
(-7250 2500);
DISPLAY 0.808511 (-7250 2500);
FORCEPROP 1 LAST PART_NUMBER AL099390004
J 0
(-7250 2300);
DISPLAY 0.489362 (-7250 2300);
PAINT SKYBLUE (-7250 2300);
FORCEPROP 1 LAST MATERIAL IC
J 0
(-7250 2225);
DISPLAY 0.489362 (-7250 2225);
PAINT SKYBLUE (-7250 2225);
FORCEPROP 2 LAST CDS_LIB pure_quanta
J 0
(-6950 1500);
DISPLAY INVISIBLE (-6950 1500);
FORCEPROP 1 LAST NEEDS_NO_SIZE TRUE
J 0
(-6950 1500);
DISPLAY 0.723404 (-6950 1500);
PAINT GREEN (-6950 1500);
DISPLAY INVISIBLE (-6950 1500);
FORCEPROP 1 LAST CDS_LMAN_SYM_OUTLINE -300,700,250,-650
J 0
(-6950 1500);
DISPLAY 0.468085 (-6950 1500);
PAINT GREEN (-6950 1500);
DISPLAY INVISIBLE (-6950 1500);
FORCEPROP 1 LAST PATH I87
J 0
(-6950 1500);
DISPLAY 0.723404 (-6950 1500);
PAINT GREEN (-6950 1500);
DISPLAY INVISIBLE (-6950 1500);
FORCEADD DNS..1
(-8875 975);
PAINT RED (-8875 975);
FORCEPROP 2 LAST CDS_LIB mstr_misc
J 0
(-8875 975);
PAINT MONO (-8875 975);
DISPLAY INVISIBLE (-8875 975);
FORCEPROP 1 LAST COMMENT_BODY TRUE
R 1
J 0
(-8800 750);
DISPLAY 0.872340 (-8800 750);
PAINT GREEN (-8800 750);
DISPLAY INVISIBLE (-8800 750);
FORCEADD DNS..1
(-5625 875);
PAINT RED (-5625 875);
FORCEPROP 2 LAST CDS_LIB mstr_misc
J 0
(-5625 875);
DISPLAY INVISIBLE (-5625 875);
FORCEPROP 1 LAST COMMENT_BODY TRUE
R 1
J 0
(-5550 650);
DISPLAY 0.872340 (-5550 650);
PAINT GREEN (-5550 650);
DISPLAY INVISIBLE (-5550 650);
FORCEADD DNS..1
(-5625 3825);
PAINT RED (-5625 3825);
FORCEPROP 2 LAST CDS_LIB mstr_misc
J 0
(-5625 3825);
DISPLAY INVISIBLE (-5625 3825);
FORCEPROP 1 LAST COMMENT_BODY TRUE
R 1
J 0
(-5550 3600);
DISPLAY 0.872340 (-5550 3600);
PAINT GREEN (-5550 3600);
DISPLAY INVISIBLE (-5550 3600);
FORCEADD DNS..1
(-5625 4275);
PAINT RED (-5625 4275);
FORCEPROP 2 LAST CDS_LIB mstr_misc
J 0
(-5625 4275);
DISPLAY INVISIBLE (-5625 4275);
FORCEPROP 1 LAST COMMENT_BODY TRUE
R 1
J 0
(-5550 4050);
DISPLAY 0.872340 (-5550 4050);
PAINT GREEN (-5550 4050);
DISPLAY INVISIBLE (-5550 4050);
FORCEADD DNS..1
(-8975 5775);
PAINT RED (-8975 5775);
FORCEPROP 2 LAST CDS_LIB mstr_misc
J 0
(-8975 5775);
DISPLAY INVISIBLE (-8975 5775);
FORCEPROP 1 LAST COMMENT_BODY TRUE
R 1
J 0
(-8900 5550);
DISPLAY 0.872340 (-8900 5550);
PAINT GREEN (-8900 5550);
DISPLAY INVISIBLE (-8900 5550);
FORCEADD QUANTA_TITLE_BLOCK_C..1
(-825 -325);
FORCEPROP 0 LAST CDS_CON_LAST_MODIFIED Fri Mar 11 14:53:28 2022
J 0
(-2710 -310);
DISPLAY INVISIBLE (-2710 -310);
FORCEPROP 1 LAST CUSTOM_TXT_CDS <CON_LAST_MODIFIED>
J 0
(-2710 -310);
DISPLAY 0.978723 (-2710 -310);
FORCEPROP 2 LAST CUSTOM_TXT_CDS <XR_PAGE_TITLE>
J 0
(-8715 4925);
DISPLAY 0.638298 (-8715 4925);
PAINT PINK (-8715 4925);
DISPLAY INVISIBLE (-8715 4925);
FORCEPROP 1 LAST CUSTOM_TXT_CDS <NAME_2>
J 0
(-4000 -275);
FORCEPROP 1 LAST CUSTOM_TXT_CDS <NAME_1>
J 0
(-4000 -150);
FORCEPROP 1 LAST CUSTOM_TXT_CDS <Q_NUMBER>
J 0
(-2228 -222);
DISPLAY 1.212766 (-2228 -222);
FORCEPROP 1 LAST CUSTOM_TXT_CDS <Q_PROJ>
J 0
(-3207 -223);
DISPLAY 1.212766 (-3207 -223);
FORCEPROP 1 LAST CUSTOM_TXT_CDS <Q_REV>
J 0
(-1009 -222);
DISPLAY 1.212766 (-1009 -222);
FORCEPROP 1 LAST CUSTOM_TXT_CDS <CON_PAGE_NUM> OF <CON_TOTAL_PAGES>
J 0
(-1271 -307);
DISPLAY 0.978723 (-1271 -307);
FORCEPROP 1 LAST Q_DEPT BU9
J 1
(-4588 -276);
DISPLAY 1.957447 (-4588 -276);
PAINT GREEN (-4588 -276);
FORCEPROP 1 LAST Q_TITLE PVDDCR_CPU1_P0 VR PHASE 1&2
J 0
(-10100 -275);
DISPLAY 2.446809 (-10100 -275);
PAINT GREEN (-10100 -275);
FORCEPROP 2 LAST CDS_LIB pure_quanta
J 0
(-825 -325);
DISPLAY INVISIBLE (-825 -325);
FORCEPROP 1 LAST CDS_LMAN_SYM_OUTLINE -9475,6775,100,-125
J 0
(-825 -325);
DISPLAY 0.468085 (-825 -325);
PAINT GREEN (-825 -325);
DISPLAY INVISIBLE (-825 -325);
FORCEPROP 2 LAST PAGE_BORDER TRUE
J 0
(-8715 4925);
DISPLAY 0.638298 (-8715 4925);
PAINT PINK (-8715 4925);
DISPLAY INVISIBLE (-8715 4925);
FORCEPROP 1 LAST COMMENT_BODY TRUE
J 0
(-813 -338);
DISPLAY 0.978723 (-813 -338);
PAINT GREEN (-813 -338);
DISPLAY INVISIBLE (-813 -338);
FORCEPROP 2 LAST CDS_XR_PAGE_TITLE CR-177 : @T6G_MB_LIB.T6G(SCH_1):PAGE177
J 0
(-8715 4925);
DISPLAY 0.638298 (-8715 4925);
PAINT PINK (-8715 4925);
DISPLAY INVISIBLE (-8715 4925);
FORCEADD DNS..1
(-5600 1300);
PAINT RED (-5600 1300);
FORCEPROP 2 LAST CDS_LIB mstr_misc
J 0
(-5600 1300);
DISPLAY INVISIBLE (-5600 1300);
FORCEPROP 1 LAST COMMENT_BODY TRUE
R 1
J 0
(-5525 1075);
DISPLAY 0.872340 (-5525 1075);
PAINT GREEN (-5525 1075);
DISPLAY INVISIBLE (-5525 1075);
FORCEADD DNS..1
(-8850 3925);
PAINT RED (-8850 3925);
FORCEPROP 2 LAST CDS_LIB mstr_misc
J 0
(-8850 3925);
PAINT MONO (-8850 3925);
DISPLAY INVISIBLE (-8850 3925);
FORCEPROP 1 LAST COMMENT_BODY TRUE
R 1
J 0
(-8775 3700);
DISPLAY 0.872340 (-8775 3700);
PAINT GREEN (-8775 3700);
DISPLAY INVISIBLE (-8775 3700);
WIRE 16 -1 (-8875 900)(-8875 825);
WIRE 16 -1 (-8850 3850)(-8850 3775);
WIRE 16 -1 (-8700 4800)(-8700 4750);
WIRE 16 -1 (-8350 5200)(-8350 5300);
WIRE 16 -1 (-8600 1825)(-8600 1775);
WIRE 16 -1 (-8250 2400)(-8250 2275);
WIRE 16 -1 (-5600 3725)(-5600 3650);
WIRE 16 -1 (-5600 775)(-5600 700);
WIRE 16 -1 (-9350 5925)(-9350 5875);
WIRE 16 -1 (-9000 5925)(-9000 5875);
WIRE 16 -1 (-9350 3925)(-9350 3975);
WIRE 16 -1 (-9475 1075)(-9475 950);
WIRE 16 -1 (-3050 5600)(-3050 5650);
WIRE 16 -1 (-3250 5600)(-3050 5600);
WIRE 16 -1 (-1575 4525)(-1575 4450);
WIRE 16 -1 (-1575 4450)(-1575 4325);
WIRE 16 -1 (-1575 4450)(-1875 4450);
WIRE 16 -1 (-1875 4350)(-1875 4450);
WIRE 16 -1 (-2300 4450)(-1875 4450);
WIRE 16 -1 (-2300 4450)(-2300 4350);
WIRE 16 -1 (-2700 4450)(-2300 4450);
WIRE 16 -1 (-2700 4450)(-2900 4450);
WIRE 16 -1 (-2700 4350)(-2700 4450);
WIRE 16 -1 (-2900 4450)(-2900 3550);
WIRE 16 -1 (-3775 4450)(-2900 4450);
WIRE 16 -1 (-2900 3550)(-4475 3550);
WIRE 17 273 (-1600 2400)(-1600 3475);
WIRE 17 273 (-3750 2400)(-1600 2400);
WIRE 17 273 (-1600 3475)(-3750 3475);
WIRE 17 273 (-3750 3475)(-3750 2400);
WIRE 16 -1 (-2125 3250)(-2125 3200);
WIRE 16 -1 (-2125 3100)(-2125 3200);
WIRE 16 -1 (-2125 3200)(-2425 3200);
WIRE 16 -1 (-2425 3100)(-2425 3200);
WIRE 16 -1 (-2750 3200)(-2425 3200);
WIRE 16 -1 (-2750 3100)(-2750 3200);
WIRE 16 -1 (-3075 3200)(-2750 3200);
WIRE 16 -1 (-3075 3100)(-3075 3200);
WIRE 16 -1 (-3425 3200)(-3075 3200);
WIRE 16 -1 (-3425 3100)(-3425 3200);
WIRE 16 -1 (-2125 2675)(-2125 2750);
WIRE 16 -1 (-2125 2900)(-2125 2750);
WIRE 16 -1 (-2125 2750)(-2425 2750);
WIRE 16 -1 (-2425 2750)(-2425 2900);
WIRE 16 -1 (-2750 2750)(-2425 2750);
WIRE 16 -1 (-2750 2900)(-2750 2750);
WIRE 16 -1 (-3075 2750)(-2750 2750);
WIRE 16 -1 (-3075 2900)(-3075 2750);
WIRE 16 -1 (-3425 2750)(-3075 2750);
WIRE 16 -1 (-3425 2900)(-3425 2750);
WIRE 16 -1 (-8700 5075)(-8125 5075);
WIRE 16 -1 (-8700 5275)(-8700 5075);
WIRE 16 -1 (-8700 5075)(-8700 5000);
WIRE 16 -1 (-8125 5075)(-8125 4800);
WIRE 16 -1 (-7475 4800)(-8125 4800);
FORCEPROP 2 LAST SIG_NAME PVDDCR_CPU1_P0_VCC1
J 0
(-8010 4810);
DISPLAY 0.489362 (-8010 4810);
FORCEPROP 2 LASTPROP $XRERR UNIQUE?
J 0
(-8250 4810);
DISPLAY 0.638298 (-8250 4810);
PAINT MONO (-8250 4810);
DISPLAY INVISIBLE (-8250 4810);
WIRE 16 -1 (-7475 4800)(-7375 4800);
WIRE 16 -1 (-7475 4600)(-7475 4800);
WIRE 16 -1 (-7375 4600)(-7475 4600);
WIRE 16 -1 (-6550 1600)(-4900 1600);
FORCEPROP 2 LAST SIG_NAME SW_PVDDCR_CPU1_P0_BOOTR2
J 0
(-6360 1610);
DISPLAY 0.489362 (-6360 1610);
FORCEPROP 2 LASTPROP $XRERR UNIQUE?
J 0
(-6600 1610);
DISPLAY 0.638298 (-6600 1610);
PAINT MONO (-6600 1610);
DISPLAY INVISIBLE (-6600 1610);
WIRE 16 -1 (-4900 1600)(-4900 1625);
WIRE 16 -1 (-4275 1500)(-5600 1500);
WIRE 16 -1 (-5600 1500)(-5600 1425);
WIRE 16 -1 (-6550 1500)(-5600 1500);
FORCEPROP 2 LAST SIG_NAME SW_PVDDCR_CPU1_P0_SW2
J 0
(-6360 1510);
DISPLAY 0.489362 (-6360 1510);
FORCEPROP 2 LASTPROP $XRERR UNIQUE?
J 0
(-6600 1510);
DISPLAY 0.638298 (-6600 1510);
PAINT MONO (-6600 1510);
DISPLAY INVISIBLE (-6600 1510);
WIRE 16 -1 (-5600 1850)(-4900 1850);
FORCEPROP 2 LAST SIG_NAME SW_PVDDCR_CPU1_P0_BOOT2_R
J 0
(-5535 1860);
DISPLAY 0.489362 (-5535 1860);
FORCEPROP 2 LASTPROP $XRERR UNIQUE?
J 0
(-5775 1860);
DISPLAY 0.638298 (-5775 1860);
PAINT MONO (-5775 1860);
DISPLAY INVISIBLE (-5775 1860);
WIRE 16 -1 (-4900 1850)(-4900 1825);
WIRE 16 -1 (-4550 2075)(-4550 2150);
WIRE 16 -1 (-4550 2300)(-4550 2150);
WIRE 16 -1 (-4925 2150)(-4550 2150);
WIRE 16 -1 (-4925 2300)(-4925 2150);
WIRE 16 -1 (-5325 2150)(-4925 2150);
WIRE 16 -1 (-5325 2300)(-5325 2150);
WIRE 16 -1 (-5325 2150)(-5725 2150);
WIRE 16 -1 (-5725 2300)(-5725 2150);
WIRE 16 -1 (-6125 2150)(-5725 2150);
WIRE 16 -1 (-6125 2300)(-6125 2150);
WIRE 16 -1 (-6525 4550)(-4950 4550);
FORCEPROP 2 LAST SIG_NAME SW_PVDDCR_CPU1_P0_BOOTR1
J 0
(-6335 4560);
DISPLAY 0.489362 (-6335 4560);
FORCEPROP 2 LASTPROP $XRERR UNIQUE?
J 0
(-6575 4560);
DISPLAY 0.638298 (-6575 4560);
PAINT MONO (-6575 4560);
DISPLAY INVISIBLE (-6575 4560);
WIRE 16 -1 (-4950 4550)(-4950 4575);
WIRE 16 -1 (-2700 4150)(-2700 4025);
WIRE 16 -1 (-2700 4025)(-2300 4025);
WIRE 16 -1 (-2300 4025)(-2300 4150);
WIRE 16 -1 (-1875 4025)(-2300 4025);
WIRE 16 -1 (-1875 4150)(-1875 4025);
WIRE 16 -1 (-1575 4025)(-1875 4025);
WIRE 16 -1 (-1575 4125)(-1575 4025);
WIRE 16 -1 (-1575 3950)(-1575 4025);
WIRE 16 -1 (-2025 1075)(-2450 1075);
WIRE 16 -1 (-2025 1075)(-2025 1200);
WIRE 16 -1 (-2025 1000)(-2025 1075);
WIRE 16 -1 (-2450 1075)(-2450 1200);
WIRE 16 -1 (-4550 600)(-2775 600);
WIRE 16 -1 (-2775 1500)(-2775 600);
WIRE 16 -1 (-3475 1500)(-2775 1500);
WIRE 16 -1 (-2450 1500)(-2775 1500);
WIRE 16 -1 (-2450 1500)(-2025 1500);
WIRE 16 -1 (-2450 1500)(-2450 1400);
WIRE 16 -1 (-2025 1550)(-2025 1500);
WIRE 16 -1 (-2025 1500)(-2025 1400);
WIRE 16 -1 (-3475 1250)(-3050 1250);
FORCEPROP 2 LAST SIG_NAME IND_CPU1_P0_CPL2
J 0
(-3435 1260);
DISPLAY 0.489362 (-3435 1260);
WIRE 16 -1 (-6525 4100)(-6000 4100);
FORCEPROP 2 LAST SIG_NAME NC_PVDDCR_CPU1_P0_GL2_1
J 0
(-6460 4110);
DISPLAY 0.489362 (-6460 4110);
FORCEPROP 2 LASTPROP $XRERR UNIQUE?
J 0
(-5970 4100);
DISPLAY 0.638298 (-5970 4100);
PAINT MONO (-5970 4100);
DISPLAY INVISIBLE (-5970 4100);
WIRE 16 -1 (-6525 4150)(-6000 4150);
FORCEPROP 2 LAST SIG_NAME NC_PVDDCR_CPU1_P0_GL1_1
J 0
(-6460 4160);
DISPLAY 0.489362 (-6460 4160);
FORCEPROP 2 LASTPROP $XRERR UNIQUE?
J 0
(-5970 4150);
DISPLAY 0.638298 (-5970 4150);
PAINT MONO (-5970 4150);
DISPLAY INVISIBLE (-5970 4150);
WIRE 16 -1 (-6525 4800)(-5775 4800);
FORCEPROP 2 LAST SIG_NAME SW_PVDDCR_CPU1_P0_BOOT1
J 0
(-6360 4810);
DISPLAY 0.489362 (-6360 4810);
FORCEPROP 2 LASTPROP $XRERR UNIQUE?
J 0
(-6600 4810);
DISPLAY 0.638298 (-6600 4810);
PAINT MONO (-6600 4810);
DISPLAY INVISIBLE (-6600 4810);
WIRE 16 -1 (-7375 4200)(-7750 4200);
FORCEPROP 2 LAST SIG_NAME NC_PVDDCR_CPU1_P0_DNC1
J 0
(-7945 4210);
DISPLAY 0.489362 (-7945 4210);
FORCEPROP 2 LASTPROP $XRERR UNIQUE?
J 0
(-7990 4200);
DISPLAY 0.638298 (-7990 4200);
PAINT MONO (-7990 4200);
DISPLAY INVISIBLE (-7990 4200);
WIRE 16 -1 (-5600 4175)(-5600 3925);
FORCEPROP 2 LAST SIG_NAME SW_PVDDCR_CPU1_P0_SW1_RC
J 0
(-5560 4010);
DISPLAY 0.489362 (-5560 4010);
FORCEPROP 2 LASTPROP $XRERR UNIQUE?
J 0
(-5800 4010);
DISPLAY 0.638298 (-5800 4010);
PAINT MONO (-5800 4010);
DISPLAY INVISIBLE (-5800 4010);
WIRE 16 -1 (-4825 1250)(-4275 1250);
FORCEPROP 2 LAST SIG_NAME IND_CPU1_P0_CPL1
J 0
(-4760 1260);
DISPLAY 0.489362 (-4760 1260);
WIRE 16 -1 (-5600 1225)(-5600 975);
FORCEPROP 2 LAST SIG_NAME SW_PVDDCR_CPU1_P0_SW2_RC
J 0
(-5560 1060);
DISPLAY 0.489362 (-5560 1060);
FORCEPROP 2 LASTPROP $XRERR UNIQUE?
J 0
(-5800 1060);
DISPLAY 0.638298 (-5800 1060);
PAINT MONO (-5800 1060);
DISPLAY INVISIBLE (-5800 1060);
WIRE 16 -1 (-6550 1200)(-6025 1200);
FORCEPROP 2 LAST SIG_NAME NC_PVDDCR_CPU1_P0_GL1_2
J 0
(-6485 1210);
DISPLAY 0.489362 (-6485 1210);
FORCEPROP 2 LASTPROP $XRERR UNIQUE?
J 0
(-5995 1200);
DISPLAY 0.638298 (-5995 1200);
PAINT MONO (-5995 1200);
DISPLAY INVISIBLE (-5995 1200);
WIRE 16 -1 (-6025 1150)(-6550 1150);
FORCEPROP 2 LAST SIG_NAME NC_PVDDCR_CPU1_P0_GL2_2
J 0
(-6485 1160);
DISPLAY 0.489362 (-6485 1160);
FORCEPROP 2 LASTPROP $XRERR UNIQUE?
J 0
(-5995 1150);
DISPLAY 0.638298 (-5995 1150);
PAINT MONO (-5995 1150);
DISPLAY INVISIBLE (-5995 1150);
WIRE 16 -1 (-6525 4000)(-6275 4000);
WIRE 16 -1 (-6275 4000)(-6275 3950);
WIRE 16 -1 (-6525 3950)(-6275 3950);
WIRE 16 -1 (-6275 3950)(-6275 3900);
WIRE 16 -1 (-6275 3900)(-6275 3850);
WIRE 16 -1 (-6525 3900)(-6275 3900);
WIRE 16 -1 (-6275 3850)(-6275 3775);
WIRE 16 -1 (-6525 3850)(-6275 3850);
WIRE 16 -1 (-6550 1050)(-6300 1050);
WIRE 16 -1 (-6300 1050)(-6300 1000);
WIRE 16 -1 (-6550 1000)(-6300 1000);
WIRE 16 -1 (-6300 1000)(-6300 950);
WIRE 16 -1 (-6300 950)(-6300 900);
WIRE 16 -1 (-6550 950)(-6300 950);
WIRE 16 -1 (-6300 900)(-6300 825);
WIRE 16 -1 (-6550 900)(-6300 900);
WIRE 16 -1 (-7400 1250)(-7775 1250);
FORCEPROP 2 LAST SIG_NAME NC_PVDDCR_CPU1_P0_DNC2
J 0
(-7970 1260);
DISPLAY 0.489362 (-7970 1260);
FORCEPROP 2 LASTPROP $XRERR UNIQUE?
J 0
(-8015 1250);
DISPLAY 0.638298 (-8015 1250);
PAINT MONO (-8015 1250);
DISPLAY INVISIBLE (-8015 1250);
WIRE 16 -1 (-7400 1000)(-8275 1000);
FORCEPROP 2 LAST SIG_NAME PVDDCR_CPU1_P0_TEMP0
J 0
(-8235 1010);
DISPLAY 0.489362 (-8235 1010);
WIRE 16 -1 (-7375 4450)(-8225 4450);
FORCEPROP 2 LAST SIG_NAME PVDDCR_CPU1_P0_IMON1
J 0
(-8185 4460);
DISPLAY 0.489362 (-8185 4460);
WIRE 16 -1 (-7375 3950)(-8225 3950);
FORCEPROP 2 LAST SIG_NAME PVDDCR_CPU1_P0_TEMP0
J 0
(-8185 3960);
DISPLAY 0.489362 (-8185 3960);
WIRE 16 -1 (-7375 3850)(-8225 3850);
FORCEPROP 2 LAST SIG_NAME PVDDCR_CPU1_P0_PWM1
J 0
(-8185 3860);
DISPLAY 0.489362 (-8185 3860);
WIRE 16 -1 (-7400 1500)(-8275 1500);
FORCEPROP 2 LAST SIG_NAME PVDDCR_CPU1_P0_IMON2
J 0
(-8235 1510);
DISPLAY 0.489362 (-8235 1510);
WIRE 16 -1 (-7475 4275)(-9350 4275);
WIRE 16 -1 (-7475 4350)(-7475 4275);
FORCEPROP 0 LAST CDS_PHYS_NET_NAME PVCCIN_CPU0_VREF
J 0
(-7475 4300);
PAINT MONO (-7475 4300);
DISPLAY INVISIBLE (-7475 4300);
WIRE 16 -1 (-9350 4275)(-9350 4175);
WIRE 16 -1 (-8225 4350)(-7475 4350);
FORCEPROP 2 LAST SIG_NAME PVDDCR_CPU1_P0_VCCS
J 0
(-8185 4360);
DISPLAY 0.489362 (-8185 4360);
WIRE 16 -1 (-7475 4350)(-7375 4350);
WIRE 16 -1 (-8600 2100)(-8025 2100);
WIRE 16 -1 (-8600 2375)(-8600 2100);
WIRE 16 -1 (-8600 2100)(-8600 2025);
WIRE 16 -1 (-8025 1850)(-8025 2100);
WIRE 16 -1 (-7500 1850)(-8025 1850);
FORCEPROP 2 LAST SIG_NAME PVDDCR_CPU1_P0_VCC2
J 0
(-7985 1860);
DISPLAY 0.489362 (-7985 1860);
FORCEPROP 2 LASTPROP $XRERR UNIQUE?
J 0
(-8225 1860);
DISPLAY 0.638298 (-8225 1860);
PAINT MONO (-8225 1860);
DISPLAY INVISIBLE (-8225 1860);
WIRE 16 -1 (-7400 1850)(-7500 1850);
WIRE 16 -1 (-7500 1650)(-7500 1850);
WIRE 16 -1 (-7400 1650)(-7500 1650);
WIRE 16 -1 (-8875 1200)(-7400 1200);
FORCEPROP 2 LAST SIG_NAME PVDDCR_CPU1_P0_LSET2
J 0
(-8235 1210);
DISPLAY 0.489362 (-8235 1210);
FORCEPROP 2 LASTPROP $XRERR UNIQUE?
J 0
(-8475 1210);
DISPLAY 0.638298 (-8475 1210);
PAINT MONO (-8475 1210);
DISPLAY INVISIBLE (-8475 1210);
WIRE 16 -1 (-8875 1200)(-8875 1100);
WIRE 16 -1 (-8850 4150)(-7375 4150);
FORCEPROP 2 LAST SIG_NAME PVDDCR_CPU1_P0_LSET1
J 0
(-8185 4160);
DISPLAY 0.489362 (-8185 4160);
FORCEPROP 2 LASTPROP $XRERR UNIQUE?
J 0
(-8425 4160);
DISPLAY 0.638298 (-8425 4160);
PAINT MONO (-8425 4160);
DISPLAY INVISIBLE (-8425 4160);
WIRE 16 -1 (-8850 4150)(-8850 4050);
WIRE 16 -1 (-8250 2700)(-8600 2700);
WIRE 16 -1 (-7925 2700)(-8250 2700);
WIRE 16 -1 (-8250 2600)(-8250 2700);
WIRE 16 -1 (-8600 2700)(-8600 2850);
WIRE 16 -1 (-8600 2575)(-8600 2700);
WIRE 16 -1 (-7925 2150)(-7925 2700);
WIRE 16 -1 (-7400 2150)(-7925 2150);
WIRE 16 -1 (-3750 5450)(-3750 5600);
WIRE 16 -1 (-3450 5600)(-3750 5600);
WIRE 16 -1 (-4150 5600)(-3750 5600);
WIRE 16 -1 (-4150 5600)(-4150 5450);
WIRE 16 -1 (-4350 5600)(-4150 5600);
WIRE 16 -1 (-4350 5650)(-4350 5600);
WIRE 16 -1 (-4350 5600)(-4575 5600);
WIRE 16 -1 (-4575 5450)(-4575 5600);
WIRE 16 -1 (-4575 5600)(-4950 5600);
WIRE 16 -1 (-4950 5450)(-4950 5600);
WIRE 16 -1 (-4950 5600)(-5350 5600);
WIRE 16 -1 (-5350 5600)(-5350 5450);
WIRE 16 -1 (-5350 5600)(-5750 5600);
WIRE 16 -1 (-5750 5450)(-5750 5600);
WIRE 16 -1 (-6150 5600)(-5750 5600);
WIRE 16 -1 (-6150 5450)(-6150 5600);
WIRE 16 -1 (-6350 5600)(-6150 5600);
WIRE 16 -1 (-6350 5600)(-6350 5100);
WIRE 16 -1 (-6525 5100)(-6350 5100);
WIRE 16 -1 (-6350 5050)(-6350 5100);
WIRE 16 -1 (-6525 5050)(-6350 5050);
WIRE 16 -1 (-3775 4200)(-3325 4200);
FORCEPROP 2 LAST SIG_NAME IND_CPU1_P0_CPL1
J 0
(-3685 4210);
DISPLAY 0.489362 (-3685 4210);
WIRE 16 -1 (-3750 5250)(-3750 5100);
WIRE 16 -1 (-4150 5100)(-3750 5100);
WIRE 16 -1 (-4150 5250)(-4150 5100);
WIRE 16 -1 (-4350 5100)(-4150 5100);
WIRE 16 -1 (-4350 5025)(-4350 5100);
WIRE 16 -1 (-4350 5100)(-4575 5100);
WIRE 16 -1 (-4575 5250)(-4575 5100);
WIRE 16 -1 (-4575 5100)(-4950 5100);
WIRE 16 -1 (-4950 5250)(-4950 5100);
WIRE 16 -1 (-4950 5100)(-5350 5100);
WIRE 16 -1 (-5350 5250)(-5350 5100);
WIRE 16 -1 (-5350 5100)(-5750 5100);
WIRE 16 -1 (-5750 5250)(-5750 5100);
WIRE 16 -1 (-6150 5100)(-5750 5100);
WIRE 16 -1 (-6150 5250)(-6150 5100);
WIRE 16 -1 (-4575 4200)(-5050 4200);
FORCEPROP 2 LAST SIG_NAME IND_CPU1_P0_CPL5
J 0
(-5060 4210);
DISPLAY 0.489362 (-5060 4210);
WIRE 16 -1 (-5600 4450)(-4575 4450);
WIRE 16 -1 (-5600 4450)(-5600 4375);
WIRE 16 -1 (-6525 4450)(-5600 4450);
FORCEPROP 2 LAST SIG_NAME SW_PVDDCR_CPU1_P0_SW1
J 0
(-6335 4460);
DISPLAY 0.489362 (-6335 4460);
FORCEPROP 2 LASTPROP $XRERR UNIQUE?
J 0
(-6575 4460);
DISPLAY 0.638298 (-6575 4460);
PAINT MONO (-6575 4460);
DISPLAY INVISIBLE (-6575 4460);
WIRE 16 -1 (-5575 4800)(-4950 4800);
FORCEPROP 2 LAST SIG_NAME SW_PVDDCR_CPU1_P0_BOOT1_R
J 0
(-5585 4810);
DISPLAY 0.489362 (-5585 4810);
FORCEPROP 2 LASTPROP $XRERR UNIQUE?
J 0
(-5825 4810);
DISPLAY 0.638298 (-5825 4810);
PAINT MONO (-5825 4810);
DISPLAY INVISIBLE (-5825 4810);
WIRE 16 -1 (-4950 4800)(-4950 4775);
WIRE 16 -1 (-7375 5100)(-7450 5100);
WIRE 16 -1 (-7450 5100)(-7450 5600);
WIRE 16 -1 (-7450 5600)(-8350 5600);
WIRE 16 -1 (-8350 5600)(-8350 5500);
WIRE 16 -1 (-8350 5600)(-8500 5600);
WIRE 16 -1 (-8500 5925)(-8500 5600);
WIRE 16 -1 (-8700 5600)(-8500 5600);
WIRE 16 -1 (-8700 5475)(-8700 5600);
WIRE 16 -1 (-8700 5600)(-9000 5600);
WIRE 16 -1 (-9000 5675)(-9000 5600);
WIRE 16 -1 (-9000 5600)(-9350 5600);
WIRE 16 -1 (-9350 5675)(-9350 5600);
WIRE 16 -1 (-4675 3550)(-5850 3550);
FORCEPROP 2 LAST SIG_NAME PVDDCR_CPU1_P0_VOS1
J 0
(-6460 4225);
DISPLAY 0.489362 (-6460 4225);
FORCEPROP 2 LASTPROP $XRERR UNIQUE?
J 0
(-6700 4225);
DISPLAY 0.638298 (-6700 4225);
PAINT MONO (-6700 4225);
DISPLAY INVISIBLE (-6700 4225);
WIRE 16 -1 (-5850 4200)(-5850 3550);
WIRE 16 -1 (-6525 4200)(-5850 4200);
WIRE 16 -1 (-4550 2500)(-4550 2650);
WIRE 16 -1 (-4550 2700)(-4550 2650);
WIRE 16 -1 (-4925 2650)(-4550 2650);
WIRE 16 -1 (-4925 2500)(-4925 2650);
WIRE 16 -1 (-5325 2650)(-4925 2650);
WIRE 16 -1 (-5325 2650)(-5325 2500);
WIRE 16 -1 (-5725 2650)(-5325 2650);
WIRE 16 -1 (-5725 2500)(-5725 2650);
WIRE 16 -1 (-6125 2650)(-5725 2650);
WIRE 16 -1 (-6125 2500)(-6125 2650);
WIRE 16 -1 (-6375 2650)(-6125 2650);
WIRE 16 -1 (-6375 2650)(-6375 2150);
WIRE 16 -1 (-6375 2100)(-6375 2150);
WIRE 16 -1 (-6550 2150)(-6375 2150);
WIRE 16 -1 (-6550 2100)(-6375 2100);
WIRE 16 -1 (-6550 1850)(-5800 1850);
FORCEPROP 2 LAST SIG_NAME SW_PVDDCR_CPU1_P0_BOOT2
J 0
(-6410 1860);
DISPLAY 0.489362 (-6410 1860);
FORCEPROP 2 LASTPROP $XRERR UNIQUE?
J 0
(-6650 1860);
DISPLAY 0.638298 (-6650 1860);
PAINT MONO (-6650 1860);
DISPLAY INVISIBLE (-6650 1860);
WIRE 16 -1 (-6550 1250)(-5900 1250);
FORCEPROP 2 LAST SIG_NAME PVDDCR_CPU1_P0_VOS2
J 0
(-6485 1275);
DISPLAY 0.489362 (-6485 1275);
FORCEPROP 2 LASTPROP $XRERR UNIQUE?
J 0
(-6725 1275);
DISPLAY 0.638298 (-6725 1275);
PAINT MONO (-6725 1275);
DISPLAY INVISIBLE (-6725 1275);
WIRE 16 -1 (-5900 1250)(-5900 600);
WIRE 16 -1 (-5900 600)(-4750 600);
WIRE 16 -1 (-7400 900)(-8275 900);
FORCEPROP 2 LAST SIG_NAME PVDDCR_CPU1_P0_PWM2
J 0
(-8235 910);
DISPLAY 0.489362 (-8235 910);
WIRE 16 -1 (-9475 1325)(-7500 1325);
WIRE 16 -1 (-9475 1325)(-9475 1275);
WIRE 16 -1 (-7500 1400)(-7500 1325);
FORCEPROP 0 LAST CDS_PHYS_NET_NAME PVCCIN_CPU0_VREF
J 0
(-7500 1350);
PAINT MONO (-7500 1350);
DISPLAY INVISIBLE (-7500 1350);
WIRE 16 -1 (-7500 1400)(-7400 1400);
WIRE 16 -1 (-8275 1400)(-7500 1400);
FORCEPROP 2 LAST SIG_NAME PVDDCR_CPU1_P0_VCCS
J 0
(-8235 1410);
DISPLAY 0.489362 (-8235 1410);
DOT 1 (-2700 4450);
DOT 1 (-3075 2750);
DOT 1 (-2750 2750);
DOT 1 (-4950 5100);
DOT 1 (-4350 5600);
DOT 1 (-1575 4450);
DOT 1 (-1875 4450);
DOT 1 (-2300 4450);
DOT 1 (-2900 4450);
DOT 1 (-1575 4025);
DOT 1 (-1875 4025);
DOT 1 (-2025 1500);
DOT 1 (-2025 1075);
DOT 1 (-2300 4025);
DOT 1 (-2125 3200);
DOT 1 (-2425 3200);
DOT 1 (-2125 2750);
DOT 1 (-3075 3200);
DOT 1 (-2450 1500);
DOT 1 (-2775 1500);
DOT 1 (-4150 5600);
DOT 1 (-4575 5600);
DOT 1 (-4150 5100);
DOT 1 (-4350 5100);
DOT 1 (-5350 5600);
DOT 1 (-5750 5600);
DOT 1 (-5350 5100);
DOT 1 (-5750 5100);
DOT 1 (-6150 5600);
DOT 1 (-6350 5100);
DOT 1 (-7475 4800);
DOT 1 (-7475 4350);
DOT 1 (-4550 2650);
DOT 1 (-4550 2150);
DOT 1 (-4925 2650);
DOT 1 (-4925 2150);
DOT 1 (-5325 2650);
DOT 1 (-5325 2150);
DOT 1 (-5725 2650);
DOT 1 (-6125 2650);
DOT 1 (-5725 2150);
DOT 1 (-6275 3900);
DOT 1 (-6275 3950);
DOT 1 (-6375 2150);
DOT 1 (-6300 1000);
DOT 1 (-6300 950);
DOT 1 (-6300 900);
DOT 1 (-7500 1850);
DOT 1 (-7500 1400);
DOT 1 (-8350 5600);
DOT 1 (-8500 5600);
DOT 1 (-8700 5600);
DOT 1 (-9000 5600);
DOT 1 (-8700 5075);
DOT 1 (-8250 2700);
DOT 1 (-8600 2700);
DOT 1 (-8600 2100);
DOT 1 (-4950 5600);
DOT 1 (-3750 5600);
DOT 1 (-4575 5100);
DOT 1 (-6275 3850);
DOT 1 (-5600 1500);
DOT 1 (-5600 4450);
DOT 1 (-2425 2750);
DOT 1 (-2750 3200);
FORCENOTE
PVDDCR_CPU1_P0_PHASE2
(-7450 2825) 0;
DISPLAY LEFT (-7450 2825);
DISPLAY 1.021277 (-7450 2825);
PAINT WHITE (-7450 2825);
FORCENOTE
3RD=CC72204MD03
(-4150 4850) 0;
DISPLAY LEFT (-4150 4850);
DISPLAY 0.638298 (-4150 4850);
PAINT WHITE (-4150 4850);
FORCENOTE
2ND=CC72204MD01
(-4150 4900) 0;
DISPLAY LEFT (-4150 4900);
DISPLAY 0.638298 (-4150 4900);
PAINT WHITE (-4150 4900);
FORCENOTE
8*11.5
(-4150 4950) 0;
DISPLAY LEFT (-4150 4950);
DISPLAY 0.638298 (-4150 4950);
PAINT WHITE (-4150 4950);
FORCENOTE
IRIPPLE:4.65A
(-4150 5000) 0;
DISPLAY LEFT (-4150 5000);
DISPLAY 0.638298 (-4150 5000);
PAINT WHITE (-4150 5000);
FORCENOTE
DCR=1-4,0.105M OHM
(-3675 4600) 0;
DISPLAY LEFT (-3675 4600);
DISPLAY 0.638298 (-3675 4600);
PAINT WHITE (-3675 4600);
FORCENOTE
DCR=2-3,0.27M OHM
(-3675 4550) 0;
DISPLAY LEFT (-3675 4550);
DISPLAY 0.638298 (-3675 4550);
PAINT WHITE (-3675 4550);
FORCENOTE
2ND=CV+15^0TZ01
(-3675 4500) 0;
DISPLAY LEFT (-3675 4500);
DISPLAY 0.638298 (-3675 4500);
PAINT WHITE (-3675 4500);
FORCENOTE
11.0*7.5*12.5
(-3675 4650) 0;
DISPLAY LEFT (-3675 4650);
DISPLAY 0.638298 (-3675 4650);
PAINT WHITE (-3675 4650);
FORCENOTE
ISAT:70A@100C
(-3675 4700) 0;
DISPLAY LEFT (-3675 4700);
DISPLAY 0.638298 (-3675 4700);
PAINT WHITE (-3675 4700);
FORCENOTE
PGL6303.151HLT
(-3675 4750) 0;
DISPLAY LEFT (-3675 4750);
DISPLAY 0.638298 (-3675 4750);
PAINT WHITE (-3675 4750);
FORCENOTE
ESR=16M OHM
(-4150 5050) 0;
DISPLAY LEFT (-4150 5050);
DISPLAY 0.638298 (-4150 5050);
PAINT WHITE (-4150 5050);
FORCENOTE
PGL6303.151HLT
(-3425 1825) 0;
DISPLAY LEFT (-3425 1825);
DISPLAY 0.638298 (-3425 1825);
PAINT WHITE (-3425 1825);
FORCENOTE
ISAT:70A@100C
(-3425 1775) 0;
DISPLAY LEFT (-3425 1775);
DISPLAY 0.638298 (-3425 1775);
PAINT WHITE (-3425 1775);
FORCENOTE
11.0*7.5*12.5
(-3425 1725) 0;
DISPLAY LEFT (-3425 1725);
DISPLAY 0.638298 (-3425 1725);
PAINT WHITE (-3425 1725);
FORCENOTE
DCR=1-4,0.105M OHM
(-3425 1675) 0;
DISPLAY LEFT (-3425 1675);
DISPLAY 0.638298 (-3425 1675);
PAINT WHITE (-3425 1675);
FORCENOTE
DCR=2-3,0.27M OHM
(-3425 1625) 0;
DISPLAY LEFT (-3425 1625);
DISPLAY 0.638298 (-3425 1625);
PAINT WHITE (-3425 1625);
FORCENOTE
PG2292.500HLT
(-3500 5550) 0;
DISPLAY LEFT (-3500 5550);
DISPLAY 0.638298 (-3500 5550);
PAINT WHITE (-3500 5550);
FORCENOTE
ISAT:70A@100C
(-3500 5500) 0;
DISPLAY LEFT (-3500 5500);
DISPLAY 0.638298 (-3500 5500);
PAINT WHITE (-3500 5500);
FORCENOTE
6.0*6.1*7.0
(-3500 5450) 0;
DISPLAY LEFT (-3500 5450);
DISPLAY 0.638298 (-3500 5450);
PAINT WHITE (-3500 5450);
FORCENOTE
2ND=CV+15^0TZ01
(-3425 1575) 0;
DISPLAY LEFT (-3425 1575);
DISPLAY 0.638298 (-3425 1575);
PAINT WHITE (-3425 1575);
FORCENOTE
DCR=0.09M OHM
(-3500 5400) 0;
DISPLAY LEFT (-3500 5400);
DISPLAY 0.638298 (-3500 5400);
PAINT WHITE (-3500 5400);
FORCENOTE
PU13,PU2,PU15,PU14,PU16,PU11=AL099390004/ISL99390FRZ-TR5935
(-2650 6025) 0;
DISPLAY LEFT (-2650 6025);
DISPLAY 0.638298 (-2650 6025);
PAINT WHITE (-2650 6025);
FORCENOTE
MAIN SOURCE:RENESAS BOM
(-2650 6100) 0;
DISPLAY LEFT (-2650 6100);
DISPLAY 0.638298 (-2650 6100);
PAINT WHITE (-2650 6100);
FORCENOTE
BOM NOTE
(-2650 6200) 0;
DISPLAY LEFT (-2650 6200);
DISPLAY 1.276596 (-2650 6200);
PAINT WHITE (-2650 6200);
FORCENOTE
PVDDCR_CPU1_P0_PHASE1
(-7325 5775) 0;
DISPLAY LEFT (-7325 5775);
DISPLAY 1.021277 (-7325 5775);
PAINT WHITE (-7325 5775);
FORCENOTE
2ND SOURCE:INFENEON BOM
(-2650 5875) 0;
DISPLAY LEFT (-2650 5875);
DISPLAY 0.638298 (-2650 5875);
PAINT WHITE (-2650 5875);
FORCENOTE
PU13,PU2,PU15,PU14,PU16,PU11 = AL021590000/TDA21590
(-2650 5800) 0;
DISPLAY LEFT (-2650 5800);
DISPLAY 0.638298 (-2650 5800);
PAINT WHITE (-2650 5800);
FORCENOTE
PR84,PR83,PR92,PR91,PR96,PR421=EMPTY
(-2650 5275) 0;
DISPLAY LEFT (-2650 5275);
DISPLAY 0.638298 (-2650 5275);
PAINT WHITE (-2650 5275);
FORCENOTE
PR443,PR81,PR82,PR89,PR90,PR95,PR420=CS00002JB38
(-2650 5200) 0;
DISPLAY LEFT (-2650 5200);
DISPLAY 0.638298 (-2650 5200);
PAINT WHITE (-2650 5200);
FORCENOTE
3RD=CVA50^0MZ08
(-3500 5300) 0;
DISPLAY LEFT (-3500 5300);
DISPLAY 0.638298 (-3500 5300);
PAINT WHITE (-3500 5300);
FORCENOTE
2ND=CVA50^0MZ07
(-3500 5350) 0;
DISPLAY LEFT (-3500 5350);
DISPLAY 0.638298 (-3500 5350);
PAINT WHITE (-3500 5350);
FORCENOTE
PR442,PC84_1,PC83_2,PC114_3,PC113_4,PC132_5,PC111_6=EMPTY
(-2650 5350) 0;
DISPLAY LEFT (-2650 5350);
DISPLAY 0.638298 (-2650 5350);
PAINT WHITE (-2650 5350);
FORCENOTE
3RD SOURCE:MPS BOM
(-2650 5425) 0;
DISPLAY LEFT (-2650 5425);
DISPLAY 0.638298 (-2650 5425);
PAINT WHITE (-2650 5425);
FORCENOTE
PC84_1,PC83_2,PC114_3,PC113_4,PC132_5,PC111_6 = EMPTY
(-2650 5575) 0;
DISPLAY LEFT (-2650 5575);
DISPLAY 0.638298 (-2650 5575);
PAINT WHITE (-2650 5575);
FORCENOTE
PR84,PR83,PR92,PR91,PR96,PR421 = EMPTY
(-2650 5650) 0;
DISPLAY LEFT (-2650 5650);
DISPLAY 0.638298 (-2650 5650);
PAINT WHITE (-2650 5650);
FORCENOTE
PR82,PR81,PR90,PR89,PR95,PR420 = CS00002JB38
(-2650 5725) 0;
DISPLAY LEFT (-2650 5725);
DISPLAY 0.638298 (-2650 5725);
PAINT WHITE (-2650 5725);
FORCENOTE
PR78,PR77,PR86,PR85,PR93,PR7 = CS00002JB38
(-2650 5500) 0;
DISPLAY LEFT (-2650 5500);
DISPLAY 0.638298 (-2650 5500);
PAINT WHITE (-2650 5500);
FORCENOTE
2ND=CH722KM8804
(-2750 2525) 0;
DISPLAY LEFT (-2750 2525);
DISPLAY 0.638298 (-2750 2525);
PAINT WHITE (-2750 2525);
FORCENOTE
MAIN=CH122KM8801
(-2750 2575) 0;
DISPLAY LEFT (-2750 2575);
DISPLAY 0.638298 (-2750 2575);
PAINT WHITE (-2750 2575);
FORCENOTE
7.3*4.3*1.9
(-2750 2625) 0;
DISPLAY LEFT (-2750 2625);
DISPLAY 0.638298 (-2750 2625);
PAINT WHITE (-2750 2625);
FORCENOTE
ESR=9M OHM
(-2750 2675) 0;
DISPLAY LEFT (-2750 2675);
DISPLAY 0.638298 (-2750 2675);
PAINT WHITE (-2750 2675);
QUIT
